FILE_TYPE = MACRO_DRAWING;
SET COLOR_WIRE YELLOW;
SET COLOR_PROP MONO;
SET COLOR_DOT WHITE;
SET COLOR_ARC YELLOW;
SET COLOR_BODY GREEN;
SET COLOR_NOTE MONO;
SET PROP_DISPLAY VALUE;
SET PAGE_NUMBER P154;
FORCEADD TTL1G32_A..1
(-2275 1150);
FORCEPROP 2 LASTPIN (-2425 1200) $PN 1
J 2
(-2435 1210);
DISPLAY 0.617021 (-2435 1210);
PAINT ORANGE (-2435 1210);
FORCEPROP 2 LASTPIN (-2425 1100) $PN 2
J 2
(-2435 1110);
DISPLAY 0.617021 (-2435 1110);
PAINT ORANGE (-2435 1110);
FORCEPROP 2 LASTPIN (-2125 1150) $PN 4
J 0
(-2115 1160);
DISPLAY 0.617021 (-2115 1160);
PAINT ORANGE (-2115 1160);
FORCEPROP 1 LAST MATERIAL IC
J 0
(-2375 1325);
DISPLAY 0.617021 (-2375 1325);
PAINT SKYBLUE (-2375 1325);
FORCEPROP 1 LAST VALUE 74LVC1G32
J 0
(-2375 1275);
DISPLAY 0.617021 (-2375 1275);
PAINT SKYBLUE (-2375 1275);
FORCEPROP 1 LAST PART_NUMBER E60229-001
J 0
(-2375 1000);
DISPLAY 0.617021 (-2375 1000);
PAINT BLUE (-2375 1000);
FORCEPROP 1 LAST LOCATION U2T2
J 0
(-2375 1375);
DISPLAY 0.617021 (-2375 1375);
PAINT AQUA (-2375 1375);
FORCEPROP 1 LAST POWER_GROUP VCC=P3V3_STBY;GND=GND
J 0
(-2375 950);
DISPLAY 0.617021 (-2375 950);
PAINT ORANGE (-2375 950);
FORCEPROP 2 LAST ROOM SB_BMC_SPI_MUX
J 0
(-2375 1425);
DISPLAY 1.021277 (-2375 1425);
PAINT ORANGE (-2375 1425);
DISPLAY INVISIBLE (-2375 1425);
FORCEPROP 1 LAST PATH I100
J 0
(-1925 1325);
DISPLAY 0.978723 (-1925 1325);
PAINT ORANGE (-1925 1325);
DISPLAY INVISIBLE (-1925 1325);
FORCEPROP 2 LAST CDS_LOCATION U2T2
J 0
(-2375 1375);
DISPLAY 0.617021 (-2375 1375);
PAINT AQUA (-2375 1375);
DISPLAY INVISIBLE (-2375 1375);
FORCEPROP 2 LAST SEC 1
J 0
(-2375 1425);
DISPLAY 0.680851 (-2375 1425);
PAINT MONO (-2375 1425);
DISPLAY INVISIBLE (-2375 1425);
FORCEPROP 2 LAST BOM_COST MIO_BIOS_MEM
J 0
(-2375 1475);
DISPLAY 1.021277 (-2375 1475);
PAINT ORANGE (-2375 1475);
DISPLAY INVISIBLE (-2375 1475);
FORCEPROP 2 LAST SEC_TYPE SOT
J 0
(-2375 1425);
DISPLAY 1.021277 (-2375 1425);
PAINT ORANGE (-2375 1425);
DISPLAY INVISIBLE (-2375 1425);
FORCEPROP 2 LAST CDS_LIB mstr_ttl
J 0
(-2275 1150);
PAINT ORANGE (-2275 1150);
DISPLAY INVISIBLE (-2275 1150);
FORCEPROP 1 LAST PACK_TYPE SOT
J 0
(-2375 1425);
DISPLAY 0.978723 (-2375 1425);
PAINT SKYBLUE (-2375 1425);
DISPLAY INVISIBLE (-2375 1425);
FORCEADD RES..1
(-1450 1875);
FORCEPROP 1 LASTPIN (-1550 1875) $PN 1
J 0
(-1538 1887);
DISPLAY 0.617021 (-1538 1887);
PAINT ORANGE (-1538 1887);
FORCEPROP 1 LASTPIN (-1350 1875) $PN 2
J 0
(-1388 1887);
DISPLAY 0.617021 (-1388 1887);
PAINT ORANGE (-1388 1887);
FORCEPROP 1 LAST WATTAGE 1/16W
J 2
(-1350 1825);
DISPLAY 0.617021 (-1350 1825);
PAINT SKYBLUE (-1350 1825);
FORCEPROP 1 LAST MATERIAL CHIP
J 0
(-1325 1825);
DISPLAY 0.617021 (-1325 1825);
PAINT SKYBLUE (-1325 1825);
FORCEPROP 1 LAST PACK_TYPE 0402
J 0
(-1225 1825);
DISPLAY 0.617021 (-1225 1825);
PAINT SKYBLUE (-1225 1825);
FORCEPROP 1 LAST TOLERANCE 1%
J 0
(-1675 1825);
DISPLAY 0.617021 (-1675 1825);
PAINT SKYBLUE (-1675 1825);
FORCEPROP 1 LAST VALUE 200.0
J 2
(-1500 1825);
DISPLAY 0.617021 (-1500 1825);
PAINT SKYBLUE (-1500 1825);
FORCEPROP 1 LAST PART_NUMBER G21796-004
J 0
(-1550 1775);
DISPLAY 0.617021 (-1550 1775);
PAINT BLUE (-1550 1775);
FORCEPROP 1 LAST LOCATION R2T13
J 0
(-1450 1925);
DISPLAY 0.617021 (-1450 1925);
PAINT AQUA (-1450 1925);
FORCEPROP 2 LAST ROOM SB_BMC_SPI_MUX
J 0
(-1450 1975);
DISPLAY 1.021277 (-1450 1975);
PAINT ORANGE (-1450 1975);
DISPLAY INVISIBLE (-1450 1975);
FORCEPROP 1 LAST PATH I101
J 0
(-1500 2025);
DISPLAY 0.978723 (-1500 2025);
PAINT WHITE (-1500 2025);
DISPLAY INVISIBLE (-1500 2025);
FORCEPROP 2 LAST CDS_LOCATION R2T13
J 0
(-1450 1925);
DISPLAY 0.617021 (-1450 1925);
PAINT AQUA (-1450 1925);
DISPLAY INVISIBLE (-1450 1925);
FORCEPROP 2 LAST SEC 1
J 0
(-1500 2075);
DISPLAY 0.680851 (-1500 2075);
PAINT MONO (-1500 2075);
DISPLAY INVISIBLE (-1500 2075);
FORCEPROP 2 LAST BOM_COST MIO_BIOS_MEM
J 0
(-1450 2025);
DISPLAY 1.021277 (-1450 2025);
PAINT ORANGE (-1450 2025);
DISPLAY INVISIBLE (-1450 2025);
FORCEPROP 2 LAST CDS_LIB mstr_discrete
J 0
(-1450 1875);
PAINT ORANGE (-1450 1875);
DISPLAY INVISIBLE (-1450 1875);
FORCEPROP 2 LAST SEC_TYPE 0402
J 0
(-1500 2075);
DISPLAY 1.021277 (-1500 2075);
PAINT ORANGE (-1500 2075);
DISPLAY INVISIBLE (-1500 2075);
FORCEADD OFFPAGE..2
(-825 1875);
FORCEPROP 2 LAST $XR0 153 
J 0
(-636 1875);
DISPLAY 0.638298 (-636 1875);
PAINT MONO (-636 1875);
FORCEPROP 2 LAST PATH I102
J 0
(-775 1950);
DISPLAY 1.021277 (-775 1950);
PAINT ORANGE (-775 1950);
DISPLAY INVISIBLE (-775 1950);
FORCEPROP 1 LAST COMMENT_BODY TRUE
J 0
(-870 1780);
DISPLAY 0.872340 (-870 1780);
PAINT GREEN (-870 1780);
DISPLAY INVISIBLE (-870 1780);
FORCEPROP 1 LAST OFFPAGE TRUE
J 0
(-500 1750);
DISPLAY 0.872340 (-500 1750);
PAINT GREEN (-500 1750);
DISPLAY INVISIBLE (-500 1750);
FORCEPROP 2 LAST CDS_LIB mstr_standard
J 0
(-825 1875);
PAINT ORANGE (-825 1875);
DISPLAY INVISIBLE (-825 1875);
FORCEADD OFFPAGE..2
(-825 1150);
FORCEPROP 2 LAST $XR0 153 
J 0
(-636 1150);
DISPLAY 0.638298 (-636 1150);
PAINT MONO (-636 1150);
FORCEPROP 2 LAST PATH I103
J 0
(-775 1225);
DISPLAY 1.021277 (-775 1225);
PAINT ORANGE (-775 1225);
DISPLAY INVISIBLE (-775 1225);
FORCEPROP 1 LAST COMMENT_BODY TRUE
J 0
(-870 1055);
DISPLAY 0.872340 (-870 1055);
PAINT GREEN (-870 1055);
DISPLAY INVISIBLE (-870 1055);
FORCEPROP 1 LAST OFFPAGE TRUE
J 0
(-500 1025);
DISPLAY 0.872340 (-500 1025);
PAINT GREEN (-500 1025);
DISPLAY INVISIBLE (-500 1025);
FORCEPROP 2 LAST CDS_LIB mstr_standard
J 0
(-825 1150);
PAINT ORANGE (-825 1150);
DISPLAY INVISIBLE (-825 1150);
FORCEADD RES..2
(-3100 2200);
FORCEPROP 1 LASTPIN (-3100 2300) $PN 1
J 0
(-3095 2262);
DISPLAY 0.617021 (-3095 2262);
PAINT ORANGE (-3095 2262);
FORCEPROP 1 LASTPIN (-3100 2100) $PN 2
J 0
(-3095 2110);
DISPLAY 0.617021 (-3095 2110);
PAINT ORANGE (-3095 2110);
FORCEPROP 1 LAST WATTAGE 1/16W
J 0
(-3060 2175);
DISPLAY 0.617021 (-3060 2175);
PAINT SKYBLUE (-3060 2175);
FORCEPROP 1 LAST MATERIAL CHIP
J 0
(-3060 2125);
DISPLAY 0.617021 (-3060 2125);
PAINT SKYBLUE (-3060 2125);
FORCEPROP 1 LAST PACK_TYPE 0402
J 0
(-3060 2025);
DISPLAY 0.617021 (-3060 2025);
PAINT SKYBLUE (-3060 2025);
FORCEPROP 1 LAST TOLERANCE 1%
J 0
(-3055 2225);
DISPLAY 0.617021 (-3055 2225);
PAINT SKYBLUE (-3055 2225);
FORCEPROP 1 LAST VALUE 4.75K
J 0
(-3055 2275);
DISPLAY 0.617021 (-3055 2275);
PAINT SKYBLUE (-3055 2275);
FORCEPROP 1 LAST PART_NUMBER G21796-072
J 0
(-3060 2075);
DISPLAY 0.617021 (-3060 2075);
PAINT BLUE (-3060 2075);
FORCEPROP 1 LAST LOCATION R2T11
J 0
(-3055 2325);
DISPLAY 0.617021 (-3055 2325);
PAINT AQUA (-3055 2325);
FORCEPROP 2 LAST ROOM SB_BMC_SPI_MUX
J 0
(-3050 2375);
DISPLAY 1.021277 (-3050 2375);
PAINT ORANGE (-3050 2375);
DISPLAY INVISIBLE (-3050 2375);
FORCEPROP 1 LAST PATH I105
J 0
(-3050 2375);
DISPLAY 0.978723 (-3050 2375);
PAINT WHITE (-3050 2375);
DISPLAY INVISIBLE (-3050 2375);
FORCEPROP 2 LAST CDS_LOCATION R2T11
J 0
(-3055 2325);
DISPLAY 0.617021 (-3055 2325);
PAINT AQUA (-3055 2325);
DISPLAY INVISIBLE (-3055 2325);
FORCEPROP 2 LAST SEC 1
J 0
(-3050 2425);
PAINT MONO (-3050 2425);
DISPLAY INVISIBLE (-3050 2425);
FORCEPROP 2 LAST BOM_COST MIO_BIOS_MEM
J 0
(-3050 2425);
DISPLAY 1.021277 (-3050 2425);
PAINT ORANGE (-3050 2425);
DISPLAY INVISIBLE (-3050 2425);
FORCEPROP 2 LAST SEC_TYPE 0402
J 0
(-3050 2425);
DISPLAY 1.021277 (-3050 2425);
PAINT ORANGE (-3050 2425);
DISPLAY INVISIBLE (-3050 2425);
FORCEPROP 2 LAST CDS_LIB mstr_discrete
J 0
(-3100 2200);
PAINT ORANGE (-3100 2200);
DISPLAY INVISIBLE (-3100 2200);
FORCEADD RES..2
R 2
(-3775 1750);
FORCEPROP 1 LASTPIN (-3775 1850) $PN 1
J 2
(-3780 1812);
DISPLAY 0.617021 (-3780 1812);
PAINT ORANGE (-3780 1812);
FORCEPROP 1 LASTPIN (-3775 1650) $PN 2
J 2
(-3780 1660);
DISPLAY 0.617021 (-3780 1660);
PAINT ORANGE (-3780 1660);
FORCEPROP 1 LAST WATTAGE 1/16W
J 2
(-3815 1725);
DISPLAY 0.617021 (-3815 1725);
PAINT SKYBLUE (-3815 1725);
FORCEPROP 1 LAST MATERIAL CHIP
J 2
(-3815 1675);
DISPLAY 0.617021 (-3815 1675);
PAINT SKYBLUE (-3815 1675);
FORCEPROP 1 LAST PACK_TYPE 0402
J 2
(-3815 1575);
DISPLAY 0.617021 (-3815 1575);
PAINT SKYBLUE (-3815 1575);
FORCEPROP 1 LAST TOLERANCE 1%
J 2
(-3820 1775);
DISPLAY 0.617021 (-3820 1775);
PAINT SKYBLUE (-3820 1775);
FORCEPROP 1 LAST VALUE 10.0K
J 2
(-3820 1825);
DISPLAY 0.617021 (-3820 1825);
PAINT SKYBLUE (-3820 1825);
FORCEPROP 1 LAST PART_NUMBER G21796-016
J 2
(-3815 1625);
DISPLAY 0.617021 (-3815 1625);
PAINT BLUE (-3815 1625);
FORCEPROP 1 LAST LOCATION R2T8
J 2
(-3820 1875);
DISPLAY 0.617021 (-3820 1875);
PAINT AQUA (-3820 1875);
FORCEPROP 2 LAST ROOM SB_BMC_SPI_MUX
J 2
(-3825 1925);
DISPLAY 1.021277 (-3825 1925);
PAINT ORANGE (-3825 1925);
DISPLAY INVISIBLE (-3825 1925);
FORCEPROP 1 LAST PATH I106
J 2
(-3825 1925);
DISPLAY 0.978723 (-3825 1925);
PAINT WHITE (-3825 1925);
DISPLAY INVISIBLE (-3825 1925);
FORCEPROP 2 LAST CDS_LOCATION R2T8
J 2
(-3820 1875);
DISPLAY 0.617021 (-3820 1875);
PAINT AQUA (-3820 1875);
DISPLAY INVISIBLE (-3820 1875);
FORCEPROP 2 LAST SEC 1
J 2
(-3825 1975);
PAINT MONO (-3825 1975);
DISPLAY INVISIBLE (-3825 1975);
FORCEPROP 2 LAST BOM_COST MIO_BIOS_MEM
J 2
(-3825 1975);
DISPLAY 1.021277 (-3825 1975);
PAINT ORANGE (-3825 1975);
DISPLAY INVISIBLE (-3825 1975);
FORCEPROP 2 LAST SEC_TYPE 0402
J 2
(-3825 1975);
DISPLAY 1.021277 (-3825 1975);
PAINT ORANGE (-3825 1975);
DISPLAY INVISIBLE (-3825 1975);
FORCEPROP 2 LAST CDS_LIB mstr_discrete
J 2
(-3775 1750);
PAINT ORANGE (-3775 1750);
DISPLAY INVISIBLE (-3775 1750);
FORCEADD OFFPAGE..1
(-4275 1475);
FORCEPROP 2 LAST $XR1 147 
J 0
(-4677 1475);
DISPLAY 0.638298 (-4677 1475);
PAINT MONO (-4677 1475);
FORCEPROP 2 LAST $XR0 120 
J 0
(-4557 1475);
DISPLAY 0.638298 (-4557 1475);
PAINT MONO (-4557 1475);
FORCEPROP 2 LAST PATH I107
J 0
(-4225 1550);
DISPLAY 1.021277 (-4225 1550);
PAINT ORANGE (-4225 1550);
DISPLAY INVISIBLE (-4225 1550);
FORCEPROP 1 LAST COMMENT_BODY TRUE
J 0
(-4150 1375);
DISPLAY 0.872340 (-4150 1375);
PAINT GREEN (-4150 1375);
DISPLAY INVISIBLE (-4150 1375);
FORCEPROP 1 LAST OFFPAGE TRUE
J 0
(-3950 1350);
DISPLAY 0.872340 (-3950 1350);
PAINT GREEN (-3950 1350);
DISPLAY INVISIBLE (-3950 1350);
FORCEPROP 2 LAST CDS_LIB mstr_standard
J 0
(-4275 1475);
PAINT ORANGE (-4275 1475);
DISPLAY INVISIBLE (-4275 1475);
FORCEADD GND..1
(-3100 1275);
FORCEPROP 3 LASTPIN (-3100 1325) SIG_NAME GND\g
J 0
(-3090 1335);
DISPLAY 0.659574 (-3090 1335);
PAINT MONO (-3090 1335);
DISPLAY INVISIBLE (-3090 1335);
FORCEPROP 1 LAST HDL_POWER GND
J 0
(-3100 1425);
DISPLAY 0.872340 (-3100 1425);
PAINT GREEN (-3100 1425);
DISPLAY INVISIBLE (-3100 1425);
FORCEPROP 1 LAST PATH I109
J 0
(-3025 1275);
DISPLAY 0.872340 (-3025 1275);
PAINT AQUA (-3025 1275);
DISPLAY INVISIBLE (-3025 1275);
FORCEPROP 1 LAST BODY_TYPE PLUMBING
J 0
(-3145 1232);
DISPLAY 0.340426 (-3145 1232);
PAINT GREEN (-3145 1232);
DISPLAY INVISIBLE (-3145 1232);
FORCEPROP 1 LAST SIZE 1B
J 0
(-3025 1225);
DISPLAY 0.872340 (-3025 1225);
PAINT AQUA (-3025 1225);
DISPLAY INVISIBLE (-3025 1225);
FORCEPROP 2 LAST CDS_LIB mstr_symbols
J 0
(-3100 1275);
PAINT ORANGE (-3100 1275);
DISPLAY INVISIBLE (-3100 1275);
FORCEPROP 1 LAST VOLTAGE 0.0V
J 0
(-3145 1232);
DISPLAY 0.340426 (-3145 1232);
PAINT SKYBLUE (-3145 1232);
DISPLAY INVISIBLE (-3145 1232);
FORCEADD P3V3_STBY..1
(-3100 2450);
FORCEPROP 3 LASTPIN (-3100 2400) SIG_NAME P3V3_STBY\g
J 0
(-3090 2410);
DISPLAY 0.659574 (-3090 2410);
PAINT MONO (-3090 2410);
DISPLAY INVISIBLE (-3090 2410);
FORCEPROP 1 LAST HDL_POWER P3V3_STBY
J 0
(-3400 2325);
DISPLAY 0.872340 (-3400 2325);
PAINT ORANGE (-3400 2325);
DISPLAY INVISIBLE (-3400 2325);
FORCEPROP 1 LAST PATH I110
J 0
(-3055 2452);
DISPLAY 0.340426 (-3055 2452);
PAINT GREEN (-3055 2452);
DISPLAY INVISIBLE (-3055 2452);
FORCEPROP 1 LAST BODY_TYPE PLUMBING
J 0
(-3145 2407);
DISPLAY 0.340426 (-3145 2407);
PAINT GREEN (-3145 2407);
DISPLAY INVISIBLE (-3145 2407);
FORCEPROP 2 LAST CDS_LIB mstr_symbols
J 0
(-3100 2450);
PAINT ORANGE (-3100 2450);
DISPLAY INVISIBLE (-3100 2450);
FORCEPROP 1 LAST SIZE 1B
J 0
(-3055 2472);
DISPLAY 0.340426 (-3055 2472);
PAINT GREEN (-3055 2472);
DISPLAY INVISIBLE (-3055 2472);
FORCEPROP 1 LAST VOLTAGE 3.3V
J 0
(-3145 2407);
DISPLAY 0.340426 (-3145 2407);
PAINT SKYBLUE (-3145 2407);
DISPLAY INVISIBLE (-3145 2407);
FORCEADD P3V3_STBY..1
(-3775 2025);
FORCEPROP 3 LASTPIN (-3775 1975) SIG_NAME P3V3_STBY\g
J 0
(-3765 1985);
DISPLAY 0.659574 (-3765 1985);
PAINT MONO (-3765 1985);
DISPLAY INVISIBLE (-3765 1985);
FORCEPROP 1 LAST HDL_POWER P3V3_STBY
J 0
(-4075 1900);
DISPLAY 0.872340 (-4075 1900);
PAINT ORANGE (-4075 1900);
DISPLAY INVISIBLE (-4075 1900);
FORCEPROP 1 LAST PATH I111
J 0
(-3730 2027);
DISPLAY 0.340426 (-3730 2027);
PAINT GREEN (-3730 2027);
DISPLAY INVISIBLE (-3730 2027);
FORCEPROP 1 LAST BODY_TYPE PLUMBING
J 0
(-3820 1982);
DISPLAY 0.340426 (-3820 1982);
PAINT GREEN (-3820 1982);
DISPLAY INVISIBLE (-3820 1982);
FORCEPROP 2 LAST CDS_LIB mstr_symbols
J 0
(-3775 2025);
PAINT ORANGE (-3775 2025);
DISPLAY INVISIBLE (-3775 2025);
FORCEPROP 1 LAST SIZE 1B
J 0
(-3730 2047);
DISPLAY 0.340426 (-3730 2047);
PAINT GREEN (-3730 2047);
DISPLAY INVISIBLE (-3730 2047);
FORCEPROP 1 LAST VOLTAGE 3.3V
J 0
(-3820 1982);
DISPLAY 0.340426 (-3820 1982);
PAINT SKYBLUE (-3820 1982);
DISPLAY INVISIBLE (-3820 1982);
FORCEADD RES..1
(-6725 3600);
FORCEPROP 1 LASTPIN (-6825 3600) $PN 1
J 0
(-6813 3612);
DISPLAY 0.617021 (-6813 3612);
PAINT MONO (-6813 3612);
FORCEPROP 1 LASTPIN (-6625 3600) $PN 2
J 0
(-6663 3612);
DISPLAY 0.617021 (-6663 3612);
PAINT MONO (-6663 3612);
FORCEPROP 1 LAST PACK_TYPE 0402
J 0
(-6475 3550);
DISPLAY 0.617021 (-6475 3550);
PAINT SKYBLUE (-6475 3550);
FORCEPROP 1 LAST TOLERANCE 5%
J 0
(-6650 3550);
DISPLAY 0.617021 (-6650 3550);
PAINT SKYBLUE (-6650 3550);
FORCEPROP 1 LAST LOCATION R8F6
J 0
(-6775 3650);
DISPLAY 0.617021 (-6775 3650);
PAINT AQUA (-6775 3650);
FORCEPROP 1 LAST MATERIAL CHIP
J 0
(-6575 3550);
DISPLAY 0.617021 (-6575 3550);
PAINT SKYBLUE (-6575 3550);
FORCEPROP 1 LAST VALUE 0.0
J 2
(-6750 3550);
DISPLAY 0.617021 (-6750 3550);
PAINT SKYBLUE (-6750 3550);
FORCEPROP 1 LAST PART_NUMBER G21497-005
J 0
(-6850 3500);
DISPLAY 0.617021 (-6850 3500);
PAINT BLUE (-6850 3500);
FORCEPROP 1 LAST WATTAGE 1/16W
J 2
(-6850 3550);
DISPLAY 0.617021 (-6850 3550);
PAINT SKYBLUE (-6850 3550);
FORCEPROP 2 LAST ROOM MIO_BIOS_MEM
J 0
(-6775 3740);
DISPLAY 0.787234 (-6775 3740);
PAINT SKYBLUE (-6775 3740);
DISPLAY INVISIBLE (-6775 3740);
FORCEPROP 1 LAST PATH I119
J 0
(-6775 3750);
DISPLAY 0.978723 (-6775 3750);
PAINT WHITE (-6775 3750);
DISPLAY INVISIBLE (-6775 3750);
FORCEPROP 2 LAST CDS_LOCATION R8F6
J 0
(-6775 3650);
DISPLAY 0.617021 (-6775 3650);
PAINT AQUA (-6775 3650);
DISPLAY INVISIBLE (-6775 3650);
FORCEPROP 2 LAST $SEC 1
J 0
(-6775 3800);
DISPLAY 0.936170 (-6775 3800);
PAINT MONO (-6775 3800);
DISPLAY INVISIBLE (-6775 3800);
FORCEPROP 2 LAST CDS_SEC 1
J 0
(-6775 3800);
DISPLAY 1.404255 (-6775 3800);
PAINT ORANGE (-6775 3800);
DISPLAY INVISIBLE (-6775 3800);
FORCEPROP 2 LAST CDS_LIB mstr_discrete
J 0
(-6725 3600);
PAINT RED (-6725 3600);
DISPLAY INVISIBLE (-6725 3600);
FORCEADD P3V3_STBY..1
(-5575 4600);
FORCEPROP 3 LASTPIN (-5575 4550) SIG_NAME P3V3_STBY\g
J 0
(-5565 4560);
DISPLAY 0.659574 (-5565 4560);
PAINT MONO (-5565 4560);
DISPLAY INVISIBLE (-5565 4560);
FORCEPROP 1 LAST HDL_POWER P3V3_STBY
J 0
(-5875 4475);
DISPLAY 0.872340 (-5875 4475);
PAINT ORANGE (-5875 4475);
DISPLAY INVISIBLE (-5875 4475);
FORCEPROP 1 LAST PATH I12
J 0
(-5530 4602);
DISPLAY 0.340426 (-5530 4602);
PAINT GREEN (-5530 4602);
DISPLAY INVISIBLE (-5530 4602);
FORCEPROP 1 LAST BODY_TYPE PLUMBING
J 0
(-5620 4557);
DISPLAY 0.340426 (-5620 4557);
PAINT GREEN (-5620 4557);
DISPLAY INVISIBLE (-5620 4557);
FORCEPROP 1 LAST SIZE 1B
J 0
(-5530 4622);
DISPLAY 0.340426 (-5530 4622);
PAINT GREEN (-5530 4622);
DISPLAY INVISIBLE (-5530 4622);
FORCEPROP 2 LAST CDS_LIB mstr_symbols
J 0
(-5575 4600);
PAINT ORANGE (-5575 4600);
DISPLAY INVISIBLE (-5575 4600);
FORCEPROP 1 LAST VOLTAGE 3.3V
J 0
(-5620 4557);
DISPLAY 0.340426 (-5620 4557);
PAINT SKYBLUE (-5620 4557);
DISPLAY INVISIBLE (-5620 4557);
FORCEADD OFFPAGE..2
R 2
(-7325 3600);
FORCEPROP 2 LAST $XR1 121 
J 0
(-7700 3600);
DISPLAY 0.638298 (-7700 3600);
PAINT MONO (-7700 3600);
FORCEPROP 2 LAST $XR0 184 
J 0
(-7580 3600);
DISPLAY 0.638298 (-7580 3600);
PAINT MONO (-7580 3600);
FORCEPROP 2 LAST PATH I123
J 0
(-7600 3650);
DISPLAY 1.021277 (-7600 3650);
PAINT ORANGE (-7600 3650);
DISPLAY INVISIBLE (-7600 3650);
FORCEPROP 1 LAST COMMENT_BODY TRUE
J 2
(-7280 3505);
DISPLAY 1.404255 (-7280 3505);
PAINT GREEN (-7280 3505);
DISPLAY INVISIBLE (-7280 3505);
FORCEPROP 1 LAST OFFPAGE TRUE
J 2
(-7650 3475);
PAINT GREEN (-7650 3475);
DISPLAY INVISIBLE (-7650 3475);
FORCEPROP 2 LAST CDS_LIB mstr_standard
J 2
(-7325 3600);
PAINT ORANGE (-7325 3600);
DISPLAY INVISIBLE (-7325 3600);
FORCEADD FET_N..8
(-3100 1575);
FORCEPROP 1 LASTPIN (-3100 1775) $PN 3
J 2
(-3047 1740);
DISPLAY 0.617021 (-3047 1740);
PAINT WHITE (-3047 1740);
FORCEPROP 1 LASTPIN (-3300 1475) $PN 1
J 2
(-3297 1490);
DISPLAY 0.617021 (-3297 1490);
PAINT WHITE (-3297 1490);
FORCEPROP 1 LASTPIN (-3100 1375) $PN 2
J 2
(-3042 1375);
DISPLAY 0.617021 (-3042 1375);
PAINT WHITE (-3042 1375);
FORCEPROP 1 LAST MATERIAL FET
J 0
(-2900 1475);
DISPLAY 0.617021 (-2900 1475);
PAINT SKYBLUE (-2900 1475);
FORCEPROP 1 LAST VALUE 2N7002
J 0
(-2900 1525);
DISPLAY 0.617021 (-2900 1525);
PAINT SKYBLUE (-2900 1525);
FORCEPROP 1 LAST PART_NUMBER C79254-001
J 0
(-2900 1375);
DISPLAY 0.617021 (-2900 1375);
PAINT BLUE (-2900 1375);
FORCEPROP 1 LAST LOCATION Q8F1
J 0
(-2900 1575);
DISPLAY 0.617021 (-2900 1575);
PAINT AQUA (-2900 1575);
FORCEPROP 0 LAST ROOM SB_BMC_SPI_MUX
J 0
(-2900 1675);
DISPLAY 1.021277 (-2900 1675);
PAINT ORANGE (-2900 1675);
DISPLAY INVISIBLE (-2900 1675);
FORCEPROP 1 LAST PATH I126
J 0
(-2900 1625);
DISPLAY 0.978723 (-2900 1625);
PAINT BLUE (-2900 1625);
DISPLAY INVISIBLE (-2900 1625);
FORCEPROP 2 LAST CDS_LOCATION Q8F1
J 0
(-2900 1575);
DISPLAY 0.617021 (-2900 1575);
PAINT AQUA (-2900 1575);
DISPLAY INVISIBLE (-2900 1575);
FORCEPROP 2 LAST SEC 1
J 0
(-2900 1675);
DISPLAY 0.680851 (-2900 1675);
PAINT MONO (-2900 1675);
DISPLAY INVISIBLE (-2900 1675);
FORCEPROP 2 LAST SEC_TYPE SOT23LF
J 0
(-2900 1675);
DISPLAY 1.021277 (-2900 1675);
PAINT ORANGE (-2900 1675);
DISPLAY INVISIBLE (-2900 1675);
FORCEPROP 0 LAST BOM_COST MIO_BIOS_MEM
J 0
(-2900 1775);
DISPLAY 1.021277 (-2900 1775);
PAINT ORANGE (-2900 1775);
DISPLAY INVISIBLE (-2900 1775);
FORCEPROP 2 LAST CDS_LIB mstr_discrete
J 0
(-3100 1575);
PAINT MONO (-3100 1575);
DISPLAY INVISIBLE (-3100 1575);
FORCEPROP 1 LAST PACK_TYPE SOT23LF
J 0
(-2900 1425);
DISPLAY 0.978723 (-2900 1425);
PAINT SKYBLUE (-2900 1425);
DISPLAY INVISIBLE (-2900 1425);
FORCEADD RES..2
R 2
(-3400 1750);
FORCEPROP 1 LAST WATTAGE 1/16W
J 2
(-3440 1725);
DISPLAY 0.617021 (-3440 1725);
PAINT SKYBLUE (-3440 1725);
FORCEPROP 1 LAST MATERIAL CHIP
J 2
(-3440 1675);
DISPLAY 0.617021 (-3440 1675);
PAINT SKYBLUE (-3440 1675);
FORCEPROP 1 LAST PACK_TYPE 0402
J 2
(-3440 1575);
DISPLAY 0.617021 (-3440 1575);
PAINT SKYBLUE (-3440 1575);
FORCEPROP 1 LAST TOLERANCE 1%
J 2
(-3445 1775);
DISPLAY 0.617021 (-3445 1775);
PAINT SKYBLUE (-3445 1775);
FORCEPROP 1 LAST VALUE 4.75K
J 2
(-3445 1825);
DISPLAY 0.617021 (-3445 1825);
PAINT SKYBLUE (-3445 1825);
FORCEPROP 1 LAST PART_NUMBER G21796-072
J 2
(-3440 1625);
DISPLAY 0.617021 (-3440 1625);
PAINT BLUE (-3440 1625);
FORCEPROP 1 LAST LOCATION R2T6
J 2
(-3445 1875);
DISPLAY 0.617021 (-3445 1875);
PAINT AQUA (-3445 1875);
FORCEPROP 1 LASTPIN (-3400 1850) $PN 1
J 2
(-3405 1812);
DISPLAY 0.787234 (-3405 1812);
PAINT ORANGE (-3405 1812);
DISPLAY INVISIBLE (-3405 1812);
FORCEPROP 1 LASTPIN (-3400 1650) $PN 2
J 2
(-3405 1660);
DISPLAY 0.787234 (-3405 1660);
PAINT ORANGE (-3405 1660);
DISPLAY INVISIBLE (-3405 1660);
FORCEPROP 2 LAST ROOM SB_BMC_SPI_MUX
J 2
(-3450 1925);
DISPLAY 1.021277 (-3450 1925);
PAINT ORANGE (-3450 1925);
DISPLAY INVISIBLE (-3450 1925);
FORCEPROP 1 LAST PATH I127
J 2
(-3450 1925);
DISPLAY 0.978723 (-3450 1925);
PAINT WHITE (-3450 1925);
DISPLAY INVISIBLE (-3450 1925);
FORCEPROP 2 LAST CDS_LOCATION R2T6
J 2
(-3445 1875);
DISPLAY 0.617021 (-3445 1875);
PAINT AQUA (-3445 1875);
DISPLAY INVISIBLE (-3445 1875);
FORCEPROP 2 LAST $SEC 1
J 0
(-3450 1975);
PAINT MONO (-3450 1975);
DISPLAY INVISIBLE (-3450 1975);
FORCEPROP 2 LAST CDS_SEC 1
J 0
(-3450 1975);
PAINT MONO (-3450 1975);
DISPLAY INVISIBLE (-3450 1975);
FORCEPROP 2 LAST BOM_COST MIO_BIOS_MEM
J 2
(-3450 1975);
DISPLAY 1.021277 (-3450 1975);
PAINT ORANGE (-3450 1975);
DISPLAY INVISIBLE (-3450 1975);
FORCEPROP 2 LAST CDS_LIB mstr_discrete
J 0
(-3400 1750);
PAINT ORANGE (-3400 1750);
DISPLAY INVISIBLE (-3400 1750);
FORCEADD RES..2
(-6250 2750);
FORCEPROP 1 LAST WATTAGE 1/16W
J 0
(-6210 2725);
DISPLAY 0.617021 (-6210 2725);
PAINT SKYBLUE (-6210 2725);
FORCEPROP 1 LASTPIN (-6250 2850) $PN 1
J 0
(-6245 2812);
DISPLAY 0.617021 (-6245 2812);
PAINT ORANGE (-6245 2812);
FORCEPROP 1 LASTPIN (-6250 2650) $PN 2
J 0
(-6245 2660);
DISPLAY 0.617021 (-6245 2660);
PAINT ORANGE (-6245 2660);
FORCEPROP 1 LAST MATERIAL CHIP
J 0
(-6210 2675);
DISPLAY 0.617021 (-6210 2675);
PAINT SKYBLUE (-6210 2675);
FORCEPROP 1 LAST PACK_TYPE 0402
J 0
(-6210 2575);
DISPLAY 0.617021 (-6210 2575);
PAINT SKYBLUE (-6210 2575);
FORCEPROP 1 LAST TOLERANCE 1%
J 0
(-6205 2775);
DISPLAY 0.617021 (-6205 2775);
PAINT SKYBLUE (-6205 2775);
FORCEPROP 1 LAST VALUE 10.0K
J 0
(-6205 2825);
DISPLAY 0.617021 (-6205 2825);
PAINT SKYBLUE (-6205 2825);
FORCEPROP 1 LAST PART_NUMBER G21796-016
J 0
(-6210 2625);
DISPLAY 0.617021 (-6210 2625);
PAINT BLUE (-6210 2625);
FORCEPROP 1 LAST LOCATION R1U6
J 0
(-6205 2875);
DISPLAY 0.617021 (-6205 2875);
PAINT AQUA (-6205 2875);
FORCEPROP 0 LAST ROOM SB_BMC_BPI_MUX
J 0
(-6200 2975);
DISPLAY 1.021277 (-6200 2975);
PAINT ORANGE (-6200 2975);
DISPLAY INVISIBLE (-6200 2975);
FORCEPROP 1 LAST PATH I128
J 0
(-6200 2925);
DISPLAY 0.978723 (-6200 2925);
PAINT WHITE (-6200 2925);
DISPLAY INVISIBLE (-6200 2925);
FORCEPROP 2 LAST CDS_LOCATION R1U6
J 0
(-6205 2875);
DISPLAY 0.617021 (-6205 2875);
PAINT AQUA (-6205 2875);
DISPLAY INVISIBLE (-6205 2875);
FORCEPROP 2 LAST SEC 1
J 0
(-6200 2975);
DISPLAY 0.680851 (-6200 2975);
PAINT MONO (-6200 2975);
DISPLAY INVISIBLE (-6200 2975);
FORCEPROP 2 LAST SEC_TYPE 0402
J 0
(-6200 2975);
DISPLAY 1.021277 (-6200 2975);
PAINT ORANGE (-6200 2975);
DISPLAY INVISIBLE (-6200 2975);
FORCEPROP 0 LAST BOM_COST MIO_BIOS_MEM
J 0
(-6200 3075);
DISPLAY 1.021277 (-6200 3075);
PAINT ORANGE (-6200 3075);
DISPLAY INVISIBLE (-6200 3075);
FORCEPROP 2 LAST CDS_LIB mstr_discrete
J 0
(-6250 2750);
PAINT MONO (-6250 2750);
DISPLAY INVISIBLE (-6250 2750);
FORCEADD GND..1
(-6250 2450);
FORCEPROP 3 LASTPIN (-6250 2500) SIG_NAME GND\g
J 0
(-6240 2510);
DISPLAY 0.659574 (-6240 2510);
PAINT MONO (-6240 2510);
DISPLAY INVISIBLE (-6240 2510);
FORCEPROP 1 LAST HDL_POWER GND
J 0
(-6250 2600);
DISPLAY 0.872340 (-6250 2600);
PAINT GREEN (-6250 2600);
DISPLAY INVISIBLE (-6250 2600);
FORCEPROP 1 LAST PATH I129
J 0
(-6175 2450);
DISPLAY 0.872340 (-6175 2450);
PAINT AQUA (-6175 2450);
DISPLAY INVISIBLE (-6175 2450);
FORCEPROP 1 LAST BODY_TYPE PLUMBING
J 0
(-6295 2407);
DISPLAY 0.340426 (-6295 2407);
PAINT GREEN (-6295 2407);
DISPLAY INVISIBLE (-6295 2407);
FORCEPROP 2 LAST CDS_LIB mstr_symbols
J 0
(-6250 2450);
PAINT MONO (-6250 2450);
DISPLAY INVISIBLE (-6250 2450);
FORCEPROP 1 LAST SIZE 1B
J 0
(-6175 2400);
DISPLAY 0.872340 (-6175 2400);
PAINT AQUA (-6175 2400);
DISPLAY INVISIBLE (-6175 2400);
FORCEPROP 1 LAST VOLTAGE 0.0V
J 0
(-6295 2407);
DISPLAY 0.340426 (-6295 2407);
PAINT SKYBLUE (-6295 2407);
DISPLAY INVISIBLE (-6295 2407);
FORCEADD GND..1
(-5400 4100);
FORCEPROP 3 LASTPIN (-5400 4150) SIG_NAME GND\g
J 0
(-5390 4160);
DISPLAY 0.659574 (-5390 4160);
PAINT MONO (-5390 4160);
DISPLAY INVISIBLE (-5390 4160);
FORCEPROP 1 LAST HDL_POWER GND
J 0
(-5400 4250);
DISPLAY 0.872340 (-5400 4250);
PAINT GREEN (-5400 4250);
DISPLAY INVISIBLE (-5400 4250);
FORCEPROP 1 LAST PATH I13
J 0
(-5325 4100);
DISPLAY 0.872340 (-5325 4100);
PAINT AQUA (-5325 4100);
DISPLAY INVISIBLE (-5325 4100);
FORCEPROP 1 LAST BODY_TYPE PLUMBING
J 0
(-5445 4057);
DISPLAY 0.340426 (-5445 4057);
PAINT GREEN (-5445 4057);
DISPLAY INVISIBLE (-5445 4057);
FORCEPROP 2 LAST CDS_LIB mstr_symbols
J 0
(-5400 4100);
PAINT ORANGE (-5400 4100);
DISPLAY INVISIBLE (-5400 4100);
FORCEPROP 1 LAST SIZE 1B
J 0
(-5325 4050);
DISPLAY 0.872340 (-5325 4050);
PAINT AQUA (-5325 4050);
DISPLAY INVISIBLE (-5325 4050);
FORCEPROP 1 LAST VOLTAGE 0.0V
J 0
(-5445 4057);
DISPLAY 0.340426 (-5445 4057);
PAINT SKYBLUE (-5445 4057);
DISPLAY INVISIBLE (-5445 4057);
FORCEADD OFFPAGE..2
(-5375 3000);
FORCEPROP 2 LAST $XR1 154 
J 0
(-5066 3000);
DISPLAY 0.638298 (-5066 3000);
PAINT MONO (-5066 3000);
FORCEPROP 2 LAST $XR0 146 
J 0
(-5186 3000);
DISPLAY 0.638298 (-5186 3000);
PAINT MONO (-5186 3000);
FORCEPROP 2 LAST PATH I130
J 0
(-5325 3075);
DISPLAY 1.021277 (-5325 3075);
PAINT ORANGE (-5325 3075);
DISPLAY INVISIBLE (-5325 3075);
FORCEPROP 1 LAST COMMENT_BODY TRUE
J 0
(-5420 2905);
DISPLAY 0.872340 (-5420 2905);
PAINT GREEN (-5420 2905);
DISPLAY INVISIBLE (-5420 2905);
FORCEPROP 1 LAST OFFPAGE TRUE
J 0
(-5050 2875);
DISPLAY 0.872340 (-5050 2875);
PAINT GREEN (-5050 2875);
DISPLAY INVISIBLE (-5050 2875);
FORCEPROP 2 LAST CDS_LIB mstr_standard
J 0
(-5375 3000);
PAINT MONO (-5375 3000);
DISPLAY INVISIBLE (-5375 3000);
FORCEADD P3V3_STBY..1
(-375 2525);
FORCEPROP 3 LASTPIN (-375 2475) SIG_NAME P3V3_STBY\g
J 0
(-365 2485);
DISPLAY 0.659574 (-365 2485);
PAINT MONO (-365 2485);
DISPLAY INVISIBLE (-365 2485);
FORCEPROP 1 LAST HDL_POWER P3V3_STBY
J 0
(-675 2400);
DISPLAY 0.872340 (-675 2400);
PAINT ORANGE (-675 2400);
DISPLAY INVISIBLE (-675 2400);
FORCEPROP 1 LAST PATH I131
J 0
(-330 2527);
DISPLAY 0.340426 (-330 2527);
PAINT GREEN (-330 2527);
DISPLAY INVISIBLE (-330 2527);
FORCEPROP 1 LAST BODY_TYPE PLUMBING
J 0
(-420 2482);
DISPLAY 0.340426 (-420 2482);
PAINT GREEN (-420 2482);
DISPLAY INVISIBLE (-420 2482);
FORCEPROP 1 LAST SIZE 1B
J 0
(-330 2547);
DISPLAY 0.340426 (-330 2547);
PAINT GREEN (-330 2547);
DISPLAY INVISIBLE (-330 2547);
FORCEPROP 2 LAST CDS_LIB mstr_symbols
J 0
(-375 2525);
PAINT ORANGE (-375 2525);
DISPLAY INVISIBLE (-375 2525);
FORCEPROP 1 LAST VOLTAGE 3.3V
J 0
(-420 2482);
DISPLAY 0.340426 (-420 2482);
PAINT SKYBLUE (-420 2482);
DISPLAY INVISIBLE (-420 2482);
FORCEADD CAP_A..1
(-375 2225);
FORCEPROP 1 LASTPIN (-375 2125) $PN 2
J 0
(-365 2105);
DISPLAY 0.617021 (-365 2105);
PAINT ORANGE (-365 2105);
FORCEPROP 1 LASTPIN (-375 2325) $PN 1
J 0
(-365 2305);
DISPLAY 0.617021 (-365 2305);
PAINT ORANGE (-365 2305);
FORCEPROP 1 LAST MATERIAL X7R
J 0
(-325 2125);
DISPLAY 0.617021 (-325 2125);
PAINT SKYBLUE (-325 2125);
FORCEPROP 1 LAST VOLTAGE 16V
J 0
(-325 2225);
DISPLAY 0.617021 (-325 2225);
PAINT SKYBLUE (-325 2225);
FORCEPROP 1 LAST PACK_TYPE 0402V
J 0
(-325 2025);
DISPLAY 0.617021 (-325 2025);
PAINT SKYBLUE (-325 2025);
FORCEPROP 1 LAST TOLERANCE 10%
J 0
(-325 2175);
DISPLAY 0.617021 (-325 2175);
PAINT SKYBLUE (-325 2175);
FORCEPROP 1 LAST VALUE 0.1UF
J 0
(-325 2275);
DISPLAY 0.617021 (-325 2275);
PAINT SKYBLUE (-325 2275);
FORCEPROP 1 LAST PART_NUMBER A36096-030
J 0
(-325 2075);
DISPLAY 0.617021 (-325 2075);
PAINT BLUE (-325 2075);
FORCEPROP 1 LAST LOCATION C2T12
J 0
(-325 2325);
DISPLAY 0.617021 (-325 2325);
PAINT AQUA (-325 2325);
FORCEPROP 2 LAST SEC 1
J 0
(-325 2375);
DISPLAY 0.680851 (-325 2375);
PAINT MONO (-325 2375);
DISPLAY INVISIBLE (-325 2375);
FORCEPROP 2 LAST SEC_TYPE 0402V
J 0
(-325 2425);
DISPLAY 1.021277 (-325 2425);
PAINT ORANGE (-325 2425);
DISPLAY INVISIBLE (-325 2425);
FORCEPROP 2 LAST CDS_SEC 1
J 0
(-325 2375);
PAINT ORANGE (-325 2375);
DISPLAY INVISIBLE (-325 2375);
FORCEPROP 2 LAST CDS_LIB dev_discrete
J 0
(-375 2225);
PAINT ORANGE (-375 2225);
DISPLAY INVISIBLE (-375 2225);
FORCEPROP 2 LAST BOM_COST MIO_BIOS_MEM
J 0
(-325 2425);
DISPLAY 1.021277 (-325 2425);
PAINT ORANGE (-325 2425);
DISPLAY INVISIBLE (-325 2425);
FORCEPROP 2 LAST CDS_LOCATION C2T12
J 0
(-325 2325);
DISPLAY 0.617021 (-325 2325);
PAINT AQUA (-325 2325);
DISPLAY INVISIBLE (-325 2325);
FORCEPROP 2 LAST ROOM SB_BMC_SPI_MUX
J 0
(-325 2375);
DISPLAY 1.021277 (-325 2375);
PAINT ORANGE (-325 2375);
DISPLAY INVISIBLE (-325 2375);
FORCEPROP 1 LAST PATH I132
J 0
(-325 2375);
DISPLAY 0.978723 (-325 2375);
PAINT WHITE (-325 2375);
DISPLAY INVISIBLE (-325 2375);
FORCEADD GND..1
(-375 1925);
FORCEPROP 3 LASTPIN (-375 1975) SIG_NAME GND\g
J 0
(-365 1985);
DISPLAY 0.659574 (-365 1985);
PAINT MONO (-365 1985);
DISPLAY INVISIBLE (-365 1985);
FORCEPROP 1 LAST HDL_POWER GND
J 0
(-375 2075);
DISPLAY 0.872340 (-375 2075);
PAINT GREEN (-375 2075);
DISPLAY INVISIBLE (-375 2075);
FORCEPROP 1 LAST PATH I133
J 0
(-300 1925);
DISPLAY 0.872340 (-300 1925);
PAINT AQUA (-300 1925);
DISPLAY INVISIBLE (-300 1925);
FORCEPROP 1 LAST BODY_TYPE PLUMBING
J 0
(-420 1882);
DISPLAY 0.340426 (-420 1882);
PAINT GREEN (-420 1882);
DISPLAY INVISIBLE (-420 1882);
FORCEPROP 1 LAST SIZE 1B
J 0
(-300 1875);
DISPLAY 0.872340 (-300 1875);
PAINT AQUA (-300 1875);
DISPLAY INVISIBLE (-300 1875);
FORCEPROP 2 LAST CDS_LIB mstr_symbols
J 0
(-375 1925);
PAINT ORANGE (-375 1925);
DISPLAY INVISIBLE (-375 1925);
FORCEPROP 1 LAST VOLTAGE 0.0V
J 0
(-420 1882);
DISPLAY 0.340426 (-420 1882);
PAINT SKYBLUE (-420 1882);
DISPLAY INVISIBLE (-420 1882);
FORCEADD P3V3_STBY..1
(-375 1700);
FORCEPROP 3 LASTPIN (-375 1650) SIG_NAME P3V3_STBY\g
J 0
(-365 1660);
DISPLAY 0.659574 (-365 1660);
PAINT MONO (-365 1660);
DISPLAY INVISIBLE (-365 1660);
FORCEPROP 1 LAST HDL_POWER P3V3_STBY
J 0
(-675 1575);
DISPLAY 0.872340 (-675 1575);
PAINT ORANGE (-675 1575);
DISPLAY INVISIBLE (-675 1575);
FORCEPROP 1 LAST PATH I134
J 0
(-330 1702);
DISPLAY 0.340426 (-330 1702);
PAINT GREEN (-330 1702);
DISPLAY INVISIBLE (-330 1702);
FORCEPROP 1 LAST BODY_TYPE PLUMBING
J 0
(-420 1657);
DISPLAY 0.340426 (-420 1657);
PAINT GREEN (-420 1657);
DISPLAY INVISIBLE (-420 1657);
FORCEPROP 1 LAST SIZE 1B
J 0
(-330 1722);
DISPLAY 0.340426 (-330 1722);
PAINT GREEN (-330 1722);
DISPLAY INVISIBLE (-330 1722);
FORCEPROP 2 LAST CDS_LIB mstr_symbols
J 0
(-375 1700);
PAINT ORANGE (-375 1700);
DISPLAY INVISIBLE (-375 1700);
FORCEPROP 1 LAST VOLTAGE 3.3V
J 0
(-420 1657);
DISPLAY 0.340426 (-420 1657);
PAINT SKYBLUE (-420 1657);
DISPLAY INVISIBLE (-420 1657);
FORCEADD CAP_A..1
(-375 1400);
FORCEPROP 1 LASTPIN (-375 1300) $PN 2
J 0
(-365 1280);
DISPLAY 0.617021 (-365 1280);
PAINT ORANGE (-365 1280);
FORCEPROP 1 LASTPIN (-375 1500) $PN 1
J 0
(-365 1480);
DISPLAY 0.617021 (-365 1480);
PAINT ORANGE (-365 1480);
FORCEPROP 1 LAST MATERIAL X7R
J 0
(-325 1300);
DISPLAY 0.617021 (-325 1300);
PAINT SKYBLUE (-325 1300);
FORCEPROP 1 LAST VOLTAGE 16V
J 0
(-325 1400);
DISPLAY 0.617021 (-325 1400);
PAINT SKYBLUE (-325 1400);
FORCEPROP 1 LAST PACK_TYPE 0402V
J 0
(-325 1200);
DISPLAY 0.617021 (-325 1200);
PAINT SKYBLUE (-325 1200);
FORCEPROP 1 LAST TOLERANCE 10%
J 0
(-325 1350);
DISPLAY 0.617021 (-325 1350);
PAINT SKYBLUE (-325 1350);
FORCEPROP 1 LAST VALUE 0.1UF
J 0
(-325 1450);
DISPLAY 0.617021 (-325 1450);
PAINT SKYBLUE (-325 1450);
FORCEPROP 1 LAST PART_NUMBER A36096-030
J 0
(-325 1250);
DISPLAY 0.617021 (-325 1250);
PAINT BLUE (-325 1250);
FORCEPROP 1 LAST LOCATION C2T8
J 0
(-325 1500);
DISPLAY 0.617021 (-325 1500);
PAINT AQUA (-325 1500);
FORCEPROP 2 LAST SEC 1
J 0
(-325 1550);
DISPLAY 0.680851 (-325 1550);
PAINT MONO (-325 1550);
DISPLAY INVISIBLE (-325 1550);
FORCEPROP 2 LAST SEC_TYPE 0402V
J 0
(-325 1600);
DISPLAY 1.021277 (-325 1600);
PAINT ORANGE (-325 1600);
DISPLAY INVISIBLE (-325 1600);
FORCEPROP 2 LAST CDS_SEC 1
J 0
(-325 1550);
PAINT ORANGE (-325 1550);
DISPLAY INVISIBLE (-325 1550);
FORCEPROP 2 LAST CDS_LIB dev_discrete
J 0
(-375 1400);
PAINT ORANGE (-375 1400);
DISPLAY INVISIBLE (-375 1400);
FORCEPROP 2 LAST BOM_COST MIO_BIOS_MEM
J 0
(-325 1600);
DISPLAY 1.021277 (-325 1600);
PAINT ORANGE (-325 1600);
DISPLAY INVISIBLE (-325 1600);
FORCEPROP 2 LAST CDS_LOCATION C2T8
J 0
(-325 1500);
DISPLAY 0.617021 (-325 1500);
PAINT AQUA (-325 1500);
DISPLAY INVISIBLE (-325 1500);
FORCEPROP 2 LAST ROOM SB_BMC_SPI_MUX
J 0
(-325 1550);
DISPLAY 1.021277 (-325 1550);
PAINT ORANGE (-325 1550);
DISPLAY INVISIBLE (-325 1550);
FORCEPROP 1 LAST PATH I135
J 0
(-325 1550);
DISPLAY 0.978723 (-325 1550);
PAINT WHITE (-325 1550);
DISPLAY INVISIBLE (-325 1550);
FORCEADD GND..1
(-375 1100);
FORCEPROP 3 LASTPIN (-375 1150) SIG_NAME GND\g
J 0
(-365 1160);
DISPLAY 0.659574 (-365 1160);
PAINT MONO (-365 1160);
DISPLAY INVISIBLE (-365 1160);
FORCEPROP 1 LAST HDL_POWER GND
J 0
(-375 1250);
DISPLAY 0.872340 (-375 1250);
PAINT GREEN (-375 1250);
DISPLAY INVISIBLE (-375 1250);
FORCEPROP 1 LAST PATH I136
J 0
(-300 1100);
DISPLAY 0.872340 (-300 1100);
PAINT AQUA (-300 1100);
DISPLAY INVISIBLE (-300 1100);
FORCEPROP 1 LAST BODY_TYPE PLUMBING
J 0
(-420 1057);
DISPLAY 0.340426 (-420 1057);
PAINT GREEN (-420 1057);
DISPLAY INVISIBLE (-420 1057);
FORCEPROP 1 LAST SIZE 1B
J 0
(-300 1050);
DISPLAY 0.872340 (-300 1050);
PAINT AQUA (-300 1050);
DISPLAY INVISIBLE (-300 1050);
FORCEPROP 2 LAST CDS_LIB mstr_symbols
J 0
(-375 1100);
PAINT ORANGE (-375 1100);
DISPLAY INVISIBLE (-375 1100);
FORCEPROP 1 LAST VOLTAGE 0.0V
J 0
(-420 1057);
DISPLAY 0.340426 (-420 1057);
PAINT SKYBLUE (-420 1057);
DISPLAY INVISIBLE (-420 1057);
FORCEADD P3V3_STBY..1
(-3400 2025);
FORCEPROP 3 LASTPIN (-3400 1975) SIG_NAME P3V3_STBY\g
J 0
(-3390 1985);
DISPLAY 0.659574 (-3390 1985);
PAINT MONO (-3390 1985);
DISPLAY INVISIBLE (-3390 1985);
FORCEPROP 1 LAST HDL_POWER P3V3_STBY
J 0
(-3700 1900);
DISPLAY 0.872340 (-3700 1900);
PAINT ORANGE (-3700 1900);
DISPLAY INVISIBLE (-3700 1900);
FORCEPROP 1 LAST PATH I137
J 0
(-3355 2027);
DISPLAY 0.340426 (-3355 2027);
PAINT GREEN (-3355 2027);
DISPLAY INVISIBLE (-3355 2027);
FORCEPROP 1 LAST BODY_TYPE PLUMBING
J 0
(-3445 1982);
DISPLAY 0.340426 (-3445 1982);
PAINT GREEN (-3445 1982);
DISPLAY INVISIBLE (-3445 1982);
FORCEPROP 2 LAST CDS_LIB mstr_symbols
J 0
(-3400 2025);
PAINT ORANGE (-3400 2025);
DISPLAY INVISIBLE (-3400 2025);
FORCEPROP 1 LAST SIZE 1B
J 0
(-3355 2047);
DISPLAY 0.340426 (-3355 2047);
PAINT GREEN (-3355 2047);
DISPLAY INVISIBLE (-3355 2047);
FORCEPROP 1 LAST VOLTAGE 3.3V
J 0
(-3445 1982);
DISPLAY 0.340426 (-3445 1982);
PAINT SKYBLUE (-3445 1982);
DISPLAY INVISIBLE (-3445 1982);
FORCEADD OFFPAGE..1
(-4275 1100);
FORCEPROP 2 LAST $XR0 154 
J 0
(-4557 1100);
DISPLAY 0.638298 (-4557 1100);
PAINT MONO (-4557 1100);
FORCEPROP 2 LAST PATH I138
J 0
(-4225 1175);
DISPLAY 1.021277 (-4225 1175);
PAINT ORANGE (-4225 1175);
DISPLAY INVISIBLE (-4225 1175);
FORCEPROP 1 LAST COMMENT_BODY TRUE
J 0
(-4150 1000);
DISPLAY 0.872340 (-4150 1000);
PAINT GREEN (-4150 1000);
DISPLAY INVISIBLE (-4150 1000);
FORCEPROP 1 LAST OFFPAGE TRUE
J 0
(-3950 975);
DISPLAY 0.872340 (-3950 975);
PAINT GREEN (-3950 975);
DISPLAY INVISIBLE (-3950 975);
FORCEPROP 2 LAST CDS_LIB mstr_standard
J 0
(-4275 1100);
PAINT ORANGE (-4275 1100);
DISPLAY INVISIBLE (-4275 1100);
FORCEADD CAP_A..1
(-5400 4350);
FORCEPROP 1 LASTPIN (-5400 4250) $PN 2
J 0
(-5390 4230);
DISPLAY 0.617021 (-5390 4230);
PAINT ORANGE (-5390 4230);
FORCEPROP 1 LASTPIN (-5400 4450) $PN 1
J 0
(-5390 4430);
DISPLAY 0.617021 (-5390 4430);
PAINT ORANGE (-5390 4430);
FORCEPROP 1 LAST MATERIAL X7R
J 0
(-5350 4250);
DISPLAY 0.617021 (-5350 4250);
PAINT SKYBLUE (-5350 4250);
FORCEPROP 1 LAST VOLTAGE 16V
J 0
(-5350 4350);
DISPLAY 0.617021 (-5350 4350);
PAINT SKYBLUE (-5350 4350);
FORCEPROP 1 LAST PACK_TYPE 0402V
J 0
(-5350 4150);
DISPLAY 0.617021 (-5350 4150);
PAINT SKYBLUE (-5350 4150);
FORCEPROP 1 LAST TOLERANCE 10%
J 0
(-5350 4300);
DISPLAY 0.617021 (-5350 4300);
PAINT SKYBLUE (-5350 4300);
FORCEPROP 1 LAST VALUE 0.1UF
J 0
(-5350 4400);
DISPLAY 0.617021 (-5350 4400);
PAINT SKYBLUE (-5350 4400);
FORCEPROP 1 LAST PART_NUMBER A36096-030
J 0
(-5350 4200);
DISPLAY 0.617021 (-5350 4200);
PAINT BLUE (-5350 4200);
FORCEPROP 1 LAST LOCATION C8E18
J 0
(-5350 4450);
DISPLAY 0.617021 (-5350 4450);
PAINT AQUA (-5350 4450);
FORCEPROP 2 LAST SEC 1
J 0
(-5350 4550);
DISPLAY 0.680851 (-5350 4550);
PAINT MONO (-5350 4550);
DISPLAY INVISIBLE (-5350 4550);
FORCEPROP 2 LAST SEC_TYPE 0402V
J 0
(-5350 4550);
DISPLAY 1.021277 (-5350 4550);
PAINT ORANGE (-5350 4550);
DISPLAY INVISIBLE (-5350 4550);
FORCEPROP 2 LAST CDS_SEC 1
J 0
(-5350 4500);
PAINT ORANGE (-5350 4500);
DISPLAY INVISIBLE (-5350 4500);
FORCEPROP 2 LAST CDS_LIB dev_discrete
J 0
(-5400 4350);
PAINT ORANGE (-5400 4350);
DISPLAY INVISIBLE (-5400 4350);
FORCEPROP 2 LAST BOM_COST MIO_BIOS_MEM
J 0
(-5350 4550);
DISPLAY 1.021277 (-5350 4550);
PAINT ORANGE (-5350 4550);
DISPLAY INVISIBLE (-5350 4550);
FORCEPROP 2 LAST CDS_LOCATION C8E18
J 0
(-5350 4450);
DISPLAY 0.617021 (-5350 4450);
PAINT AQUA (-5350 4450);
DISPLAY INVISIBLE (-5350 4450);
FORCEPROP 2 LAST ROOM SB_BMC_SPI_MUX
J 0
(-5350 4500);
DISPLAY 1.021277 (-5350 4500);
PAINT ORANGE (-5350 4500);
DISPLAY INVISIBLE (-5350 4500);
FORCEPROP 1 LAST PATH I14
J 0
(-5350 4500);
DISPLAY 0.978723 (-5350 4500);
PAINT WHITE (-5350 4500);
DISPLAY INVISIBLE (-5350 4500);
FORCEADD RES..1
(-1450 1150);
FORCEPROP 1 LASTPIN (-1550 1150) $PN 1
J 0
(-1538 1162);
DISPLAY 0.617021 (-1538 1162);
PAINT ORANGE (-1538 1162);
FORCEPROP 1 LASTPIN (-1350 1150) $PN 2
J 0
(-1388 1162);
DISPLAY 0.617021 (-1388 1162);
PAINT ORANGE (-1388 1162);
FORCEPROP 1 LAST WATTAGE 1/16W
J 2
(-1325 1100);
DISPLAY 0.617021 (-1325 1100);
PAINT SKYBLUE (-1325 1100);
FORCEPROP 1 LAST MATERIAL CHIP
J 0
(-1300 1100);
DISPLAY 0.617021 (-1300 1100);
PAINT SKYBLUE (-1300 1100);
FORCEPROP 1 LAST PACK_TYPE 0402
J 0
(-1200 1100);
DISPLAY 0.617021 (-1200 1100);
PAINT SKYBLUE (-1200 1100);
FORCEPROP 1 LAST TOLERANCE 1.0%
J 0
(-1650 1100);
DISPLAY 0.617021 (-1650 1100);
PAINT SKYBLUE (-1650 1100);
FORCEPROP 1 LAST VALUE 75
J 2
(-1500 1100);
DISPLAY 0.617021 (-1500 1100);
PAINT SKYBLUE (-1500 1100);
FORCEPROP 1 LAST PART_NUMBER G21796-267
J 0
(-1525 1050);
DISPLAY 0.617021 (-1525 1050);
PAINT BLUE (-1525 1050);
FORCEPROP 1 LAST LOCATION R2T9
J 0
(-1450 1200);
DISPLAY 0.617021 (-1450 1200);
PAINT AQUA (-1450 1200);
FORCEPROP 2 LAST ROOM SB_BMC_SPI_MUX
J 0
(-1450 1250);
DISPLAY 1.021277 (-1450 1250);
PAINT ORANGE (-1450 1250);
DISPLAY INVISIBLE (-1450 1250);
FORCEPROP 1 LAST PATH I62
J 0
(-1500 1300);
DISPLAY 0.978723 (-1500 1300);
PAINT WHITE (-1500 1300);
DISPLAY INVISIBLE (-1500 1300);
FORCEPROP 2 LAST CDS_LOCATION R2T9
J 0
(-1450 1200);
DISPLAY 0.617021 (-1450 1200);
PAINT AQUA (-1450 1200);
DISPLAY INVISIBLE (-1450 1200);
FORCEPROP 2 LAST SEC 1
J 0
(-1500 1350);
DISPLAY 0.680851 (-1500 1350);
PAINT MONO (-1500 1350);
DISPLAY INVISIBLE (-1500 1350);
FORCEPROP 2 LAST SEC_TYPE 0402
J 0
(-1500 1350);
DISPLAY 1.021277 (-1500 1350);
PAINT ORANGE (-1500 1350);
DISPLAY INVISIBLE (-1500 1350);
FORCEPROP 2 LAST CDS_LIB mstr_discrete
J 0
(-1450 1150);
PAINT ORANGE (-1450 1150);
DISPLAY INVISIBLE (-1450 1150);
FORCEPROP 2 LAST BOM_COST MIO_BIOS_MEM
J 0
(-1450 1300);
DISPLAY 1.021277 (-1450 1300);
PAINT ORANGE (-1450 1300);
DISPLAY INVISIBLE (-1450 1300);
FORCEADD OFFPAGE..5
R 2
(-4850 3900);
FORCEPROP 2 LAST $XR0 153 
J 0
(-4661 3900);
DISPLAY 0.638298 (-4661 3900);
PAINT MONO (-4661 3900);
FORCEPROP 2 LAST PATH I70
J 2
(-4600 3950);
DISPLAY 1.021277 (-4600 3950);
PAINT ORANGE (-4600 3950);
DISPLAY INVISIBLE (-4600 3950);
FORCEPROP 1 LAST COMMENT_BODY TRUE
J 2
(-4950 3825);
DISPLAY 0.872340 (-4950 3825);
PAINT GREEN (-4950 3825);
DISPLAY INVISIBLE (-4950 3825);
FORCEPROP 1 LAST OFFPAGE TRUE
J 2
(-5175 3775);
DISPLAY 0.872340 (-5175 3775);
PAINT GREEN (-5175 3775);
DISPLAY INVISIBLE (-5175 3775);
FORCEPROP 2 LAST CDS_LIB mstr_standard
J 2
(-4850 3900);
PAINT ORANGE (-4850 3900);
DISPLAY INVISIBLE (-4850 3900);
FORCEADD OFFPAGE..5
R 2
(-4850 3800);
FORCEPROP 2 LAST $XR0 153 
J 0
(-4661 3800);
DISPLAY 0.638298 (-4661 3800);
PAINT MONO (-4661 3800);
FORCEPROP 2 LAST PATH I71
J 2
(-4600 3850);
DISPLAY 1.021277 (-4600 3850);
PAINT ORANGE (-4600 3850);
DISPLAY INVISIBLE (-4600 3850);
FORCEPROP 1 LAST COMMENT_BODY TRUE
J 2
(-4950 3725);
DISPLAY 0.872340 (-4950 3725);
PAINT GREEN (-4950 3725);
DISPLAY INVISIBLE (-4950 3725);
FORCEPROP 1 LAST OFFPAGE TRUE
J 2
(-5175 3675);
DISPLAY 0.872340 (-5175 3675);
PAINT GREEN (-5175 3675);
DISPLAY INVISIBLE (-5175 3675);
FORCEPROP 2 LAST CDS_LIB mstr_standard
J 2
(-4850 3800);
PAINT ORANGE (-4850 3800);
DISPLAY INVISIBLE (-4850 3800);
FORCEADD OFFPAGE..5
R 2
(-4850 3700);
FORCEPROP 2 LAST $XR0 154 
J 0
(-4661 3700);
DISPLAY 0.638298 (-4661 3700);
PAINT MONO (-4661 3700);
FORCEPROP 2 LAST PATH I72
J 2
(-4600 3750);
DISPLAY 1.021277 (-4600 3750);
PAINT ORANGE (-4600 3750);
DISPLAY INVISIBLE (-4600 3750);
FORCEPROP 1 LAST COMMENT_BODY TRUE
J 2
(-4950 3625);
DISPLAY 0.872340 (-4950 3625);
PAINT GREEN (-4950 3625);
DISPLAY INVISIBLE (-4950 3625);
FORCEPROP 1 LAST OFFPAGE TRUE
J 2
(-5175 3575);
DISPLAY 0.872340 (-5175 3575);
PAINT GREEN (-5175 3575);
DISPLAY INVISIBLE (-5175 3575);
FORCEPROP 2 LAST CDS_LIB mstr_standard
J 2
(-4850 3700);
PAINT ORANGE (-4850 3700);
DISPLAY INVISIBLE (-4850 3700);
FORCEADD OFFPAGE..1
R 2
(-4850 3600);
FORCEPROP 2 LAST $XR0 153 
J 0
(-4664 3600);
DISPLAY 0.638298 (-4664 3600);
PAINT MONO (-4664 3600);
FORCEPROP 2 LAST PATH I73
J 2
(-4600 3650);
DISPLAY 1.021277 (-4600 3650);
PAINT ORANGE (-4600 3650);
DISPLAY INVISIBLE (-4600 3650);
FORCEPROP 1 LAST COMMENT_BODY TRUE
J 2
(-4975 3500);
DISPLAY 0.872340 (-4975 3500);
PAINT GREEN (-4975 3500);
DISPLAY INVISIBLE (-4975 3500);
FORCEPROP 1 LAST OFFPAGE TRUE
J 2
(-5175 3475);
DISPLAY 0.872340 (-5175 3475);
PAINT GREEN (-5175 3475);
DISPLAY INVISIBLE (-5175 3475);
FORCEPROP 2 LAST CDS_LIB mstr_standard
J 2
(-4850 3600);
PAINT ORANGE (-4850 3600);
DISPLAY INVISIBLE (-4850 3600);
FORCEADD PI3B3257A..1
R 2
(-5900 3700);
FORCEPROP 2 LASTPIN (-6100 4000) $PN 15
J 2
(-6110 4010);
DISPLAY 0.617021 (-6110 4010);
PAINT ORANGE (-6110 4010);
FORCEPROP 2 LASTPIN (-5700 3500) $PN 8
J 0
(-5690 3510);
DISPLAY 0.617021 (-5690 3510);
PAINT ORANGE (-5690 3510);
FORCEPROP 2 LASTPIN (-6100 3900) $PN 2
J 2
(-6110 3910);
DISPLAY 0.617021 (-6110 3910);
PAINT ORANGE (-6110 3910);
FORCEPROP 2 LASTPIN (-6100 3850) $PN 3
J 2
(-6110 3860);
DISPLAY 0.617021 (-6110 3860);
PAINT ORANGE (-6110 3860);
FORCEPROP 2 LASTPIN (-6100 3800) $PN 5
J 2
(-6110 3810);
DISPLAY 0.617021 (-6110 3810);
PAINT ORANGE (-6110 3810);
FORCEPROP 2 LASTPIN (-6100 3750) $PN 6
J 2
(-6110 3760);
DISPLAY 0.617021 (-6110 3760);
PAINT ORANGE (-6110 3760);
FORCEPROP 2 LASTPIN (-6100 3700) $PN 11
J 2
(-6110 3710);
DISPLAY 0.617021 (-6110 3710);
PAINT ORANGE (-6110 3710);
FORCEPROP 2 LASTPIN (-6100 3650) $PN 10
J 2
(-6110 3660);
DISPLAY 0.617021 (-6110 3660);
PAINT ORANGE (-6110 3660);
FORCEPROP 2 LASTPIN (-6100 3600) $PN 14
J 2
(-6110 3610);
DISPLAY 0.617021 (-6110 3610);
PAINT ORANGE (-6110 3610);
FORCEPROP 2 LASTPIN (-6100 3550) $PN 13
J 2
(-6110 3560);
DISPLAY 0.617021 (-6110 3560);
PAINT ORANGE (-6110 3560);
FORCEPROP 2 LASTPIN (-6100 3950) $PN 1
J 2
(-6110 3960);
DISPLAY 0.617021 (-6110 3960);
PAINT ORANGE (-6110 3960);
FORCEPROP 2 LASTPIN (-5700 4000) $PN 16
J 0
(-5690 4010);
DISPLAY 0.617021 (-5690 4010);
PAINT ORANGE (-5690 4010);
FORCEPROP 2 LASTPIN (-5700 3900) $PN 4
J 0
(-5690 3910);
DISPLAY 0.617021 (-5690 3910);
PAINT ORANGE (-5690 3910);
FORCEPROP 2 LASTPIN (-5700 3800) $PN 7
J 0
(-5690 3810);
DISPLAY 0.617021 (-5690 3810);
PAINT ORANGE (-5690 3810);
FORCEPROP 2 LASTPIN (-5700 3700) $PN 9
J 0
(-5690 3710);
DISPLAY 0.617021 (-5690 3710);
PAINT ORANGE (-5690 3710);
FORCEPROP 2 LASTPIN (-5700 3600) $PN 12
J 0
(-5690 3610);
DISPLAY 0.617021 (-5690 3610);
PAINT ORANGE (-5690 3610);
FORCEPROP 1 LAST MATERIAL IC
J 2
(-5750 4100);
DISPLAY 0.617021 (-5750 4100);
PAINT SKYBLUE (-5750 4100);
FORCEPROP 1 LAST PART_NUMBER E16801-001
J 2
(-5750 3400);
DISPLAY 0.617021 (-5750 3400);
PAINT BLUE (-5750 3400);
FORCEPROP 1 LAST LOCATION U8F1
J 2
(-5850 4125);
DISPLAY 0.617021 (-5850 4125);
PAINT AQUA (-5850 4125);
FORCEPROP 2 LAST ROOM SB_BMC_SPI_MUX
J 0
(-5750 4175);
DISPLAY 1.021277 (-5750 4175);
PAINT ORANGE (-5750 4175);
DISPLAY INVISIBLE (-5750 4175);
FORCEPROP 1 LAST PATH I74
J 2
(-6025 4075);
DISPLAY 0.468085 (-6025 4075);
PAINT GREEN (-6025 4075);
DISPLAY INVISIBLE (-6025 4075);
FORCEPROP 2 LAST CDS_LOCATION U8F1
J 2
(-5750 4125);
DISPLAY 0.617021 (-5750 4125);
PAINT AQUA (-5750 4125);
DISPLAY INVISIBLE (-5750 4125);
FORCEPROP 2 LAST SEC 1
J 2
(-5750 4150);
DISPLAY 0.680851 (-5750 4150);
PAINT MONO (-5750 4150);
DISPLAY INVISIBLE (-5750 4150);
FORCEPROP 2 LAST CDS_LIB mstr_digital
J 2
(-5900 3700);
PAINT ORANGE (-5900 3700);
DISPLAY INVISIBLE (-5900 3700);
FORCEPROP 2 LAST SEC_TYPE TSSOPLF
J 2
(-5750 4150);
DISPLAY 1.021277 (-5750 4150);
PAINT ORANGE (-5750 4150);
DISPLAY INVISIBLE (-5750 4150);
FORCEPROP 2 LAST BOM_COST MIO_BIOS_MEM
J 0
(-5750 4225);
DISPLAY 1.021277 (-5750 4225);
PAINT ORANGE (-5750 4225);
DISPLAY INVISIBLE (-5750 4225);
FORCEPROP 1 LAST PACK_TYPE TSSOPLF
J 2
(-5750 4150);
DISPLAY 0.468085 (-5750 4150);
PAINT SKYBLUE (-5750 4150);
DISPLAY INVISIBLE (-5750 4150);
FORCEADD PI3B3257A..1
R 2
(-2000 3875);
FORCEPROP 2 LASTPIN (-2200 4175) $PN 15
J 2
(-2210 4185);
DISPLAY 0.617021 (-2210 4185);
PAINT ORANGE (-2210 4185);
FORCEPROP 2 LASTPIN (-1800 3675) $PN 8
J 0
(-1790 3685);
DISPLAY 0.617021 (-1790 3685);
PAINT ORANGE (-1790 3685);
FORCEPROP 2 LASTPIN (-2200 4075) $PN 2
J 2
(-2210 4085);
DISPLAY 0.617021 (-2210 4085);
PAINT ORANGE (-2210 4085);
FORCEPROP 2 LASTPIN (-2200 4025) $PN 3
J 2
(-2210 4035);
DISPLAY 0.617021 (-2210 4035);
PAINT ORANGE (-2210 4035);
FORCEPROP 2 LASTPIN (-2200 3975) $PN 5
J 2
(-2210 3985);
DISPLAY 0.617021 (-2210 3985);
PAINT ORANGE (-2210 3985);
FORCEPROP 2 LASTPIN (-2200 3925) $PN 6
J 2
(-2210 3935);
DISPLAY 0.617021 (-2210 3935);
PAINT ORANGE (-2210 3935);
FORCEPROP 2 LASTPIN (-2200 3875) $PN 11
J 2
(-2210 3885);
DISPLAY 0.617021 (-2210 3885);
PAINT ORANGE (-2210 3885);
FORCEPROP 2 LASTPIN (-2200 3825) $PN 10
J 2
(-2210 3835);
DISPLAY 0.617021 (-2210 3835);
PAINT ORANGE (-2210 3835);
FORCEPROP 2 LASTPIN (-2200 3775) $PN 14
J 2
(-2210 3785);
DISPLAY 0.617021 (-2210 3785);
PAINT ORANGE (-2210 3785);
FORCEPROP 2 LASTPIN (-2200 3725) $PN 13
J 2
(-2210 3735);
DISPLAY 0.617021 (-2210 3735);
PAINT ORANGE (-2210 3735);
FORCEPROP 2 LASTPIN (-2200 4125) $PN 1
J 2
(-2210 4135);
DISPLAY 0.617021 (-2210 4135);
PAINT ORANGE (-2210 4135);
FORCEPROP 2 LASTPIN (-1800 4175) $PN 16
J 0
(-1790 4185);
DISPLAY 0.617021 (-1790 4185);
PAINT ORANGE (-1790 4185);
FORCEPROP 2 LASTPIN (-1800 4075) $PN 4
J 0
(-1790 4085);
DISPLAY 0.617021 (-1790 4085);
PAINT ORANGE (-1790 4085);
FORCEPROP 2 LASTPIN (-1800 3975) $PN 7
J 0
(-1790 3985);
DISPLAY 0.617021 (-1790 3985);
PAINT ORANGE (-1790 3985);
FORCEPROP 2 LASTPIN (-1800 3875) $PN 9
J 0
(-1790 3885);
DISPLAY 0.617021 (-1790 3885);
PAINT ORANGE (-1790 3885);
FORCEPROP 2 LASTPIN (-1800 3775) $PN 12
J 0
(-1790 3785);
DISPLAY 0.617021 (-1790 3785);
PAINT ORANGE (-1790 3785);
FORCEPROP 1 LAST MATERIAL IC
J 2
(-1850 4275);
DISPLAY 0.617021 (-1850 4275);
PAINT SKYBLUE (-1850 4275);
FORCEPROP 1 LAST PART_NUMBER E16801-001
J 2
(-1875 3575);
DISPLAY 0.617021 (-1875 3575);
PAINT BLUE (-1875 3575);
FORCEPROP 1 LAST LOCATION U2T1
J 2
(-1975 4300);
DISPLAY 0.617021 (-1975 4300);
PAINT AQUA (-1975 4300);
FORCEPROP 2 LAST ROOM SB_BMC_SPI_MUX
J 0
(-1850 4350);
DISPLAY 1.021277 (-1850 4350);
PAINT ORANGE (-1850 4350);
DISPLAY INVISIBLE (-1850 4350);
FORCEPROP 1 LAST PATH I75
J 2
(-2125 4250);
DISPLAY 0.468085 (-2125 4250);
PAINT GREEN (-2125 4250);
DISPLAY INVISIBLE (-2125 4250);
FORCEPROP 2 LAST CDS_LOCATION U2T1
J 2
(-1850 4300);
DISPLAY 0.617021 (-1850 4300);
PAINT AQUA (-1850 4300);
DISPLAY INVISIBLE (-1850 4300);
FORCEPROP 2 LAST SEC 1
J 2
(-1850 4325);
DISPLAY 0.680851 (-1850 4325);
PAINT MONO (-1850 4325);
DISPLAY INVISIBLE (-1850 4325);
FORCEPROP 2 LAST CDS_LIB mstr_digital
J 2
(-2000 3875);
PAINT ORANGE (-2000 3875);
DISPLAY INVISIBLE (-2000 3875);
FORCEPROP 2 LAST SEC_TYPE TSSOPLF
J 2
(-1850 4325);
DISPLAY 1.021277 (-1850 4325);
PAINT ORANGE (-1850 4325);
DISPLAY INVISIBLE (-1850 4325);
FORCEPROP 2 LAST BOM_COST MIO_BIOS_MEM
J 0
(-1850 4400);
DISPLAY 1.021277 (-1850 4400);
PAINT ORANGE (-1850 4400);
DISPLAY INVISIBLE (-1850 4400);
FORCEPROP 1 LAST PACK_TYPE TSSOPLF
J 2
(-1850 4325);
DISPLAY 0.468085 (-1850 4325);
PAINT SKYBLUE (-1850 4325);
DISPLAY INVISIBLE (-1850 4325);
FORCEADD OFFPAGE..4
R 2
(-7325 3950);
FORCEPROP 2 LAST $XR1 154 
J 0
(-7697 3950);
DISPLAY 0.638298 (-7697 3950);
PAINT MONO (-7697 3950);
FORCEPROP 2 LAST $XR0 146 
J 0
(-7577 3950);
DISPLAY 0.638298 (-7577 3950);
PAINT MONO (-7577 3950);
FORCEPROP 2 LAST PATH I76
J 2
(-7525 4000);
DISPLAY 1.021277 (-7525 4000);
PAINT ORANGE (-7525 4000);
DISPLAY INVISIBLE (-7525 4000);
FORCEPROP 1 LAST COMMENT_BODY TRUE
J 2
(-7300 3850);
DISPLAY 0.872340 (-7300 3850);
PAINT GREEN (-7300 3850);
DISPLAY INVISIBLE (-7300 3850);
FORCEPROP 1 LAST OFFPAGE TRUE
J 2
(-7650 3825);
DISPLAY 0.872340 (-7650 3825);
PAINT GREEN (-7650 3825);
DISPLAY INVISIBLE (-7650 3825);
FORCEPROP 2 LAST CDS_LIB mstr_standard
J 2
(-7325 3950);
PAINT ORANGE (-7325 3950);
DISPLAY INVISIBLE (-7325 3950);
FORCEADD OFFPAGE..4
R 2
(-7325 3900);
FORCEPROP 2 LAST $XR1 184 
J 0
(-7697 3900);
DISPLAY 0.638298 (-7697 3900);
PAINT MONO (-7697 3900);
FORCEPROP 2 LAST $XR0 121 
J 0
(-7577 3900);
DISPLAY 0.638298 (-7577 3900);
PAINT MONO (-7577 3900);
FORCEPROP 2 LAST PATH I77
J 2
(-7650 3950);
DISPLAY 1.021277 (-7650 3950);
PAINT ORANGE (-7650 3950);
DISPLAY INVISIBLE (-7650 3950);
FORCEPROP 1 LAST COMMENT_BODY TRUE
J 2
(-7300 3800);
DISPLAY 0.872340 (-7300 3800);
PAINT GREEN (-7300 3800);
DISPLAY INVISIBLE (-7300 3800);
FORCEPROP 1 LAST OFFPAGE TRUE
J 2
(-7650 3775);
DISPLAY 0.872340 (-7650 3775);
PAINT GREEN (-7650 3775);
DISPLAY INVISIBLE (-7650 3775);
FORCEPROP 2 LAST CDS_LIB mstr_standard
J 2
(-7325 3900);
PAINT ORANGE (-7325 3900);
DISPLAY INVISIBLE (-7325 3900);
FORCEADD OFFPAGE..4
R 2
(-7325 3850);
FORCEPROP 2 LAST $XR0 146 
J 0
(-7577 3850);
DISPLAY 0.638298 (-7577 3850);
PAINT MONO (-7577 3850);
FORCEPROP 2 LAST PATH I78
J 2
(-7525 3900);
DISPLAY 1.021277 (-7525 3900);
PAINT ORANGE (-7525 3900);
DISPLAY INVISIBLE (-7525 3900);
FORCEPROP 1 LAST COMMENT_BODY TRUE
J 2
(-7300 3750);
DISPLAY 0.872340 (-7300 3750);
PAINT GREEN (-7300 3750);
DISPLAY INVISIBLE (-7300 3750);
FORCEPROP 1 LAST OFFPAGE TRUE
J 2
(-7650 3725);
DISPLAY 0.872340 (-7650 3725);
PAINT GREEN (-7650 3725);
DISPLAY INVISIBLE (-7650 3725);
FORCEPROP 2 LAST CDS_LIB mstr_standard
J 2
(-7325 3850);
PAINT ORANGE (-7325 3850);
DISPLAY INVISIBLE (-7325 3850);
FORCEADD OFFPAGE..4
R 2
(-7325 3800);
FORCEPROP 2 LAST $XR3 184 
J 0
(-7937 3800);
DISPLAY 0.638298 (-7937 3800);
PAINT MONO (-7937 3800);
FORCEPROP 2 LAST $XR2 125 
J 0
(-7817 3800);
DISPLAY 0.638298 (-7817 3800);
PAINT MONO (-7817 3800);
FORCEPROP 2 LAST $XR1 121 
J 0
(-7697 3800);
DISPLAY 0.638298 (-7697 3800);
PAINT MONO (-7697 3800);
FORCEPROP 2 LAST $XR0 111 
J 0
(-7577 3800);
DISPLAY 0.638298 (-7577 3800);
PAINT MONO (-7577 3800);
FORCEPROP 2 LAST PATH I79
J 2
(-7650 3850);
DISPLAY 1.021277 (-7650 3850);
PAINT ORANGE (-7650 3850);
DISPLAY INVISIBLE (-7650 3850);
FORCEPROP 1 LAST COMMENT_BODY TRUE
J 2
(-7300 3700);
DISPLAY 0.872340 (-7300 3700);
PAINT GREEN (-7300 3700);
DISPLAY INVISIBLE (-7300 3700);
FORCEPROP 1 LAST OFFPAGE TRUE
J 2
(-7650 3675);
DISPLAY 0.872340 (-7650 3675);
PAINT GREEN (-7650 3675);
DISPLAY INVISIBLE (-7650 3675);
FORCEPROP 2 LAST CDS_LIB mstr_standard
J 2
(-7325 3800);
PAINT ORANGE (-7325 3800);
DISPLAY INVISIBLE (-7325 3800);
FORCEADD OFFPAGE..2
R 2
(-7325 3550);
FORCEPROP 2 LAST $XR0 146 
J 0
(-7580 3550);
DISPLAY 0.638298 (-7580 3550);
PAINT MONO (-7580 3550);
FORCEPROP 2 LAST PATH I81
J 2
(-7525 3600);
DISPLAY 1.021277 (-7525 3600);
PAINT ORANGE (-7525 3600);
DISPLAY INVISIBLE (-7525 3600);
FORCEPROP 1 LAST COMMENT_BODY TRUE
J 2
(-7280 3455);
DISPLAY 0.872340 (-7280 3455);
PAINT GREEN (-7280 3455);
DISPLAY INVISIBLE (-7280 3455);
FORCEPROP 1 LAST OFFPAGE TRUE
J 2
(-7650 3425);
DISPLAY 0.872340 (-7650 3425);
PAINT GREEN (-7650 3425);
DISPLAY INVISIBLE (-7650 3425);
FORCEPROP 2 LAST CDS_LIB mstr_standard
J 2
(-7325 3550);
PAINT ORANGE (-7325 3550);
DISPLAY INVISIBLE (-7325 3550);
FORCEADD OFFPAGE..4
R 2
(-7325 3750);
FORCEPROP 2 LAST $XR0 146 
J 0
(-7577 3750);
DISPLAY 0.638298 (-7577 3750);
PAINT MONO (-7577 3750);
FORCEPROP 2 LAST PATH I82
J 2
(-7525 3800);
DISPLAY 1.021277 (-7525 3800);
PAINT ORANGE (-7525 3800);
DISPLAY INVISIBLE (-7525 3800);
FORCEPROP 1 LAST COMMENT_BODY TRUE
J 2
(-7300 3650);
DISPLAY 0.872340 (-7300 3650);
PAINT GREEN (-7300 3650);
DISPLAY INVISIBLE (-7300 3650);
FORCEPROP 1 LAST OFFPAGE TRUE
J 2
(-7650 3625);
DISPLAY 0.872340 (-7650 3625);
PAINT GREEN (-7650 3625);
DISPLAY INVISIBLE (-7650 3625);
FORCEPROP 2 LAST CDS_LIB mstr_standard
J 2
(-7325 3750);
PAINT ORANGE (-7325 3750);
DISPLAY INVISIBLE (-7325 3750);
FORCEADD OFFPAGE..4
R 2
(-7325 3700);
FORCEPROP 2 LAST $XR0 121 
J 0
(-7577 3700);
DISPLAY 0.638298 (-7577 3700);
PAINT MONO (-7577 3700);
FORCEPROP 2 LAST PATH I83
J 2
(-7650 3750);
DISPLAY 1.021277 (-7650 3750);
PAINT ORANGE (-7650 3750);
DISPLAY INVISIBLE (-7650 3750);
FORCEPROP 1 LAST COMMENT_BODY TRUE
J 2
(-7300 3600);
DISPLAY 0.872340 (-7300 3600);
PAINT GREEN (-7300 3600);
DISPLAY INVISIBLE (-7300 3600);
FORCEPROP 1 LAST OFFPAGE TRUE
J 2
(-7650 3575);
DISPLAY 0.872340 (-7650 3575);
PAINT GREEN (-7650 3575);
DISPLAY INVISIBLE (-7650 3575);
FORCEPROP 2 LAST CDS_LIB mstr_standard
J 2
(-7325 3700);
PAINT ORANGE (-7325 3700);
DISPLAY INVISIBLE (-7325 3700);
FORCEADD OFFPAGE..4
R 2
(-7325 3650);
FORCEPROP 2 LAST $XR0 146 
J 0
(-7577 3650);
DISPLAY 0.638298 (-7577 3650);
PAINT MONO (-7577 3650);
FORCEPROP 2 LAST PATH I84
J 2
(-7525 3700);
DISPLAY 1.021277 (-7525 3700);
PAINT ORANGE (-7525 3700);
DISPLAY INVISIBLE (-7525 3700);
FORCEPROP 1 LAST COMMENT_BODY TRUE
J 2
(-7300 3550);
DISPLAY 0.872340 (-7300 3550);
PAINT GREEN (-7300 3550);
DISPLAY INVISIBLE (-7300 3550);
FORCEPROP 1 LAST OFFPAGE TRUE
J 2
(-7650 3525);
DISPLAY 0.872340 (-7650 3525);
PAINT GREEN (-7650 3525);
DISPLAY INVISIBLE (-7650 3525);
FORCEPROP 2 LAST CDS_LIB mstr_standard
J 2
(-7325 3650);
PAINT ORANGE (-7325 3650);
DISPLAY INVISIBLE (-7325 3650);
FORCEADD GND..1
(-5625 3325);
FORCEPROP 3 LASTPIN (-5625 3375) SIG_NAME GND\g
J 0
(-5615 3385);
DISPLAY 0.659574 (-5615 3385);
PAINT MONO (-5615 3385);
DISPLAY INVISIBLE (-5615 3385);
FORCEPROP 1 LAST HDL_POWER GND
J 0
(-5625 3475);
DISPLAY 0.872340 (-5625 3475);
PAINT GREEN (-5625 3475);
DISPLAY INVISIBLE (-5625 3475);
FORCEPROP 1 LAST PATH I85
J 0
(-5550 3325);
DISPLAY 0.872340 (-5550 3325);
PAINT AQUA (-5550 3325);
DISPLAY INVISIBLE (-5550 3325);
FORCEPROP 1 LAST BODY_TYPE PLUMBING
J 0
(-5670 3282);
DISPLAY 0.340426 (-5670 3282);
PAINT GREEN (-5670 3282);
DISPLAY INVISIBLE (-5670 3282);
FORCEPROP 1 LAST SIZE 1B
J 0
(-5550 3275);
DISPLAY 0.872340 (-5550 3275);
PAINT AQUA (-5550 3275);
DISPLAY INVISIBLE (-5550 3275);
FORCEPROP 2 LAST CDS_LIB mstr_symbols
J 0
(-5625 3325);
PAINT ORANGE (-5625 3325);
DISPLAY INVISIBLE (-5625 3325);
FORCEPROP 1 LAST VOLTAGE 0.0V
J 0
(-5670 3282);
DISPLAY 0.340426 (-5670 3282);
PAINT SKYBLUE (-5670 3282);
DISPLAY INVISIBLE (-5670 3282);
FORCEADD GND..1
(-6175 3325);
FORCEPROP 3 LASTPIN (-6175 3375) SIG_NAME GND\g
J 0
(-6165 3385);
DISPLAY 0.659574 (-6165 3385);
PAINT MONO (-6165 3385);
DISPLAY INVISIBLE (-6165 3385);
FORCEPROP 1 LAST HDL_POWER GND
J 0
(-6175 3475);
DISPLAY 0.872340 (-6175 3475);
PAINT GREEN (-6175 3475);
DISPLAY INVISIBLE (-6175 3475);
FORCEPROP 1 LAST PATH I86
J 0
(-6100 3325);
DISPLAY 0.872340 (-6100 3325);
PAINT AQUA (-6100 3325);
DISPLAY INVISIBLE (-6100 3325);
FORCEPROP 1 LAST BODY_TYPE PLUMBING
J 0
(-6220 3282);
DISPLAY 0.340426 (-6220 3282);
PAINT GREEN (-6220 3282);
DISPLAY INVISIBLE (-6220 3282);
FORCEPROP 1 LAST SIZE 1B
J 0
(-6100 3275);
DISPLAY 0.872340 (-6100 3275);
PAINT AQUA (-6100 3275);
DISPLAY INVISIBLE (-6100 3275);
FORCEPROP 2 LAST CDS_LIB mstr_symbols
J 0
(-6175 3325);
PAINT ORANGE (-6175 3325);
DISPLAY INVISIBLE (-6175 3325);
FORCEPROP 1 LAST VOLTAGE 0.0V
J 0
(-6220 3282);
DISPLAY 0.340426 (-6220 3282);
PAINT SKYBLUE (-6220 3282);
DISPLAY INVISIBLE (-6220 3282);
FORCEADD OFFPAGE..5
R 2
(-950 4075);
FORCEPROP 2 LAST $XR0 153 
J 0
(-761 4075);
DISPLAY 0.638298 (-761 4075);
PAINT MONO (-761 4075);
FORCEPROP 2 LAST PATH I87
J 2
(-700 4125);
DISPLAY 1.021277 (-700 4125);
PAINT ORANGE (-700 4125);
DISPLAY INVISIBLE (-700 4125);
FORCEPROP 1 LAST COMMENT_BODY TRUE
J 2
(-1050 4000);
DISPLAY 0.872340 (-1050 4000);
PAINT GREEN (-1050 4000);
DISPLAY INVISIBLE (-1050 4000);
FORCEPROP 1 LAST OFFPAGE TRUE
J 2
(-1275 3950);
DISPLAY 0.872340 (-1275 3950);
PAINT GREEN (-1275 3950);
DISPLAY INVISIBLE (-1275 3950);
FORCEPROP 2 LAST CDS_LIB mstr_standard
J 2
(-950 4075);
PAINT ORANGE (-950 4075);
DISPLAY INVISIBLE (-950 4075);
FORCEADD OFFPAGE..5
R 2
(-950 3975);
FORCEPROP 2 LAST $XR0 153 
J 0
(-761 3975);
DISPLAY 0.638298 (-761 3975);
PAINT MONO (-761 3975);
FORCEPROP 2 LAST PATH I88
J 2
(-700 4025);
DISPLAY 1.021277 (-700 4025);
PAINT ORANGE (-700 4025);
DISPLAY INVISIBLE (-700 4025);
FORCEPROP 1 LAST COMMENT_BODY TRUE
J 2
(-1050 3900);
DISPLAY 0.872340 (-1050 3900);
PAINT GREEN (-1050 3900);
DISPLAY INVISIBLE (-1050 3900);
FORCEPROP 1 LAST OFFPAGE TRUE
J 2
(-1275 3850);
DISPLAY 0.872340 (-1275 3850);
PAINT GREEN (-1275 3850);
DISPLAY INVISIBLE (-1275 3850);
FORCEPROP 2 LAST CDS_LIB mstr_standard
J 2
(-950 3975);
PAINT ORANGE (-950 3975);
DISPLAY INVISIBLE (-950 3975);
FORCEADD OFFPAGE..4
R 2
(-3500 4125);
FORCEPROP 2 LAST $XR1 154 
J 0
(-3872 4125);
DISPLAY 0.638298 (-3872 4125);
PAINT MONO (-3872 4125);
FORCEPROP 2 LAST $XR0 146 
J 0
(-3752 4125);
DISPLAY 0.638298 (-3752 4125);
PAINT MONO (-3752 4125);
FORCEPROP 2 LAST PATH I89
J 2
(-3700 4175);
DISPLAY 1.021277 (-3700 4175);
PAINT ORANGE (-3700 4175);
DISPLAY INVISIBLE (-3700 4175);
FORCEPROP 1 LAST COMMENT_BODY TRUE
J 2
(-3475 4025);
DISPLAY 0.872340 (-3475 4025);
PAINT GREEN (-3475 4025);
DISPLAY INVISIBLE (-3475 4025);
FORCEPROP 1 LAST OFFPAGE TRUE
J 2
(-3825 4000);
DISPLAY 0.872340 (-3825 4000);
PAINT GREEN (-3825 4000);
DISPLAY INVISIBLE (-3825 4000);
FORCEPROP 2 LAST CDS_LIB mstr_standard
J 2
(-3500 4125);
PAINT ORANGE (-3500 4125);
DISPLAY INVISIBLE (-3500 4125);
FORCEADD OFFPAGE..4
R 2
(-3500 4075);
FORCEPROP 2 LAST $XR2 125 
J 0
(-3992 4075);
DISPLAY 0.638298 (-3992 4075);
PAINT MONO (-3992 4075);
FORCEPROP 2 LAST $XR1 121 
J 0
(-3872 4075);
DISPLAY 0.638298 (-3872 4075);
PAINT MONO (-3872 4075);
FORCEPROP 2 LAST $XR0 111 
J 0
(-3752 4075);
DISPLAY 0.638298 (-3752 4075);
PAINT MONO (-3752 4075);
FORCEPROP 2 LAST PATH I90
J 2
(-3950 4125);
DISPLAY 1.021277 (-3950 4125);
PAINT ORANGE (-3950 4125);
DISPLAY INVISIBLE (-3950 4125);
FORCEPROP 1 LAST COMMENT_BODY TRUE
J 2
(-3475 3975);
DISPLAY 0.872340 (-3475 3975);
PAINT GREEN (-3475 3975);
DISPLAY INVISIBLE (-3475 3975);
FORCEPROP 1 LAST OFFPAGE TRUE
J 2
(-3825 3950);
DISPLAY 0.872340 (-3825 3950);
PAINT GREEN (-3825 3950);
DISPLAY INVISIBLE (-3825 3950);
FORCEPROP 2 LAST CDS_LIB mstr_standard
J 2
(-3500 4075);
PAINT ORANGE (-3500 4075);
DISPLAY INVISIBLE (-3500 4075);
FORCEADD OFFPAGE..4
R 2
(-3500 3975);
FORCEPROP 2 LAST $XR1 125 
J 0
(-3872 3975);
DISPLAY 0.638298 (-3872 3975);
PAINT MONO (-3872 3975);
FORCEPROP 2 LAST $XR0 121 
J 0
(-3752 3975);
DISPLAY 0.638298 (-3752 3975);
PAINT MONO (-3752 3975);
FORCEPROP 2 LAST PATH I91
J 2
(-3825 4025);
DISPLAY 1.021277 (-3825 4025);
PAINT ORANGE (-3825 4025);
DISPLAY INVISIBLE (-3825 4025);
FORCEPROP 1 LAST COMMENT_BODY TRUE
J 2
(-3475 3875);
DISPLAY 0.872340 (-3475 3875);
PAINT GREEN (-3475 3875);
DISPLAY INVISIBLE (-3475 3875);
FORCEPROP 1 LAST OFFPAGE TRUE
J 2
(-3825 3850);
DISPLAY 0.872340 (-3825 3850);
PAINT GREEN (-3825 3850);
DISPLAY INVISIBLE (-3825 3850);
FORCEPROP 2 LAST CDS_LIB mstr_standard
J 2
(-3500 3975);
PAINT ORANGE (-3500 3975);
DISPLAY INVISIBLE (-3500 3975);
FORCEADD RES..1
(-2925 3975);
FORCEPROP 1 LASTPIN (-3025 3975) $PN 1
J 0
(-3013 3987);
DISPLAY 0.617021 (-3013 3987);
PAINT ORANGE (-3013 3987);
FORCEPROP 1 LAST WATTAGE 1/16W
J 2
(-3000 3925);
DISPLAY 0.617021 (-3000 3925);
PAINT SKYBLUE (-3000 3925);
FORCEPROP 1 LAST MATERIAL CHIP
J 0
(-3100 3875);
DISPLAY 0.617021 (-3100 3875);
PAINT SKYBLUE (-3100 3875);
FORCEPROP 1 LAST LOCATION R2T2
J 0
(-2975 3825);
DISPLAY 0.617021 (-2975 3825);
PAINT AQUA (-2975 3825);
FORCEPROP 1 LAST VALUE 0.0
J 2
(-2950 3925);
DISPLAY 0.617021 (-2950 3925);
PAINT SKYBLUE (-2950 3925);
FORCEPROP 1 LASTPIN (-2825 3975) $PN 2
J 0
(-2863 3987);
DISPLAY 0.617021 (-2863 3987);
PAINT ORANGE (-2863 3987);
FORCEPROP 1 LAST PART_NUMBER G21497-005
J 0
(-2900 3875);
DISPLAY 0.617021 (-2900 3875);
PAINT BLUE (-2900 3875);
FORCEPROP 1 LAST TOLERANCE 5%
J 0
(-2825 3925);
DISPLAY 0.617021 (-2825 3925);
PAINT SKYBLUE (-2825 3925);
FORCEPROP 1 LAST PACK_TYPE 0402
J 0
(-2750 3925);
DISPLAY 0.617021 (-2750 3925);
PAINT SKYBLUE (-2750 3925);
FORCEPROP 2 LAST ROOM SB_BMC_SPI_MUX
J 0
(-2725 3975);
DISPLAY 1.021277 (-2725 3975);
PAINT ORANGE (-2725 3975);
DISPLAY INVISIBLE (-2725 3975);
FORCEPROP 1 LAST PATH I92
J 0
(-2975 4125);
DISPLAY 0.978723 (-2975 4125);
PAINT WHITE (-2975 4125);
DISPLAY INVISIBLE (-2975 4125);
FORCEPROP 2 LAST CDS_LOCATION R2T2
J 0
(-2975 3825);
DISPLAY 0.617021 (-2975 3825);
PAINT AQUA (-2975 3825);
DISPLAY INVISIBLE (-2975 3825);
FORCEPROP 2 LAST SEC 1
J 0
(-2975 4175);
PAINT MONO (-2975 4175);
DISPLAY INVISIBLE (-2975 4175);
FORCEPROP 2 LAST BOM_COST MIO_BIOS_MEM
J 0
(-2725 4025);
DISPLAY 1.021277 (-2725 4025);
PAINT ORANGE (-2725 4025);
DISPLAY INVISIBLE (-2725 4025);
FORCEPROP 2 LAST CDS_LIB mstr_discrete
J 0
(-2925 3975);
PAINT ORANGE (-2925 3975);
DISPLAY INVISIBLE (-2925 3975);
FORCEPROP 2 LAST SEC_TYPE 0402
J 0
(-2975 4175);
DISPLAY 1.021277 (-2975 4175);
PAINT ORANGE (-2975 4175);
DISPLAY INVISIBLE (-2975 4175);
FORCEADD RES..1
(-2925 4075);
FORCEPROP 1 LASTPIN (-3025 4075) $PN 1
J 0
(-3013 4087);
DISPLAY 0.617021 (-3013 4087);
PAINT ORANGE (-3013 4087);
FORCEPROP 1 LASTPIN (-2825 4075) $PN 2
J 0
(-2863 4087);
DISPLAY 0.617021 (-2863 4087);
PAINT ORANGE (-2863 4087);
FORCEPROP 1 LAST WATTAGE 1/16W
J 2
(-3000 4025);
DISPLAY 0.617021 (-3000 4025);
PAINT SKYBLUE (-3000 4025);
FORCEPROP 1 LAST MATERIAL CHIP
J 0
(-3100 3975);
DISPLAY 0.617021 (-3100 3975);
PAINT SKYBLUE (-3100 3975);
FORCEPROP 1 LAST TOLERANCE 5%
J 0
(-2825 4025);
DISPLAY 0.617021 (-2825 4025);
PAINT SKYBLUE (-2825 4025);
FORCEPROP 1 LAST VALUE 0.0
J 2
(-2950 4025);
DISPLAY 0.617021 (-2950 4025);
PAINT SKYBLUE (-2950 4025);
FORCEPROP 1 LAST LOCATION R2R12
J 0
(-2975 4125);
DISPLAY 0.617021 (-2975 4125);
PAINT AQUA (-2975 4125);
FORCEPROP 1 LAST PACK_TYPE 0402
J 0
(-2750 4025);
DISPLAY 0.617021 (-2750 4025);
PAINT SKYBLUE (-2750 4025);
FORCEPROP 1 LAST PART_NUMBER G21497-005
J 0
(-3425 4025);
DISPLAY 0.617021 (-3425 4025);
PAINT BLUE (-3425 4025);
FORCEPROP 2 LAST ROOM SB_BMC_SPI_MUX
J 0
(-2975 4175);
DISPLAY 1.021277 (-2975 4175);
PAINT ORANGE (-2975 4175);
DISPLAY INVISIBLE (-2975 4175);
FORCEPROP 1 LAST PATH I93
J 0
(-2975 4225);
DISPLAY 0.978723 (-2975 4225);
PAINT WHITE (-2975 4225);
DISPLAY INVISIBLE (-2975 4225);
FORCEPROP 2 LAST CDS_LOCATION R2R12
J 0
(-2975 4125);
DISPLAY 0.617021 (-2975 4125);
PAINT AQUA (-2975 4125);
DISPLAY INVISIBLE (-2975 4125);
FORCEPROP 2 LAST SEC 1
J 0
(-2975 4275);
PAINT MONO (-2975 4275);
DISPLAY INVISIBLE (-2975 4275);
FORCEPROP 2 LAST BOM_COST MIO_BIOS_MEM
J 0
(-2975 4225);
DISPLAY 1.021277 (-2975 4225);
PAINT ORANGE (-2975 4225);
DISPLAY INVISIBLE (-2975 4225);
FORCEPROP 2 LAST CDS_LIB mstr_discrete
J 0
(-2925 4075);
PAINT ORANGE (-2925 4075);
DISPLAY INVISIBLE (-2925 4075);
FORCEPROP 2 LAST SEC_TYPE 0402
J 0
(-2975 4275);
DISPLAY 1.021277 (-2975 4275);
PAINT ORANGE (-2975 4275);
DISPLAY INVISIBLE (-2975 4275);
FORCEADD CAP_A..1
(-1500 4525);
FORCEPROP 1 LASTPIN (-1500 4425) $PN 2
J 0
(-1490 4405);
DISPLAY 0.617021 (-1490 4405);
PAINT ORANGE (-1490 4405);
FORCEPROP 1 LASTPIN (-1500 4625) $PN 1
J 0
(-1490 4605);
DISPLAY 0.617021 (-1490 4605);
PAINT ORANGE (-1490 4605);
FORCEPROP 1 LAST MATERIAL X7R
J 0
(-1450 4425);
DISPLAY 0.617021 (-1450 4425);
PAINT SKYBLUE (-1450 4425);
FORCEPROP 1 LAST VOLTAGE 16V
J 0
(-1450 4525);
DISPLAY 0.617021 (-1450 4525);
PAINT SKYBLUE (-1450 4525);
FORCEPROP 1 LAST PACK_TYPE 0402V
J 0
(-1450 4325);
DISPLAY 0.617021 (-1450 4325);
PAINT SKYBLUE (-1450 4325);
FORCEPROP 1 LAST TOLERANCE 10%
J 0
(-1450 4475);
DISPLAY 0.617021 (-1450 4475);
PAINT SKYBLUE (-1450 4475);
FORCEPROP 1 LAST VALUE 0.1UF
J 0
(-1450 4575);
DISPLAY 0.617021 (-1450 4575);
PAINT SKYBLUE (-1450 4575);
FORCEPROP 1 LAST PART_NUMBER A36096-030
J 0
(-1450 4375);
DISPLAY 0.617021 (-1450 4375);
PAINT BLUE (-1450 4375);
FORCEPROP 1 LAST LOCATION C2T1
J 0
(-1450 4625);
DISPLAY 0.617021 (-1450 4625);
PAINT AQUA (-1450 4625);
FORCEPROP 2 LAST SEC 1
J 0
(-1450 4725);
DISPLAY 0.680851 (-1450 4725);
PAINT MONO (-1450 4725);
DISPLAY INVISIBLE (-1450 4725);
FORCEPROP 2 LAST SEC_TYPE 0402V
J 0
(-1450 4725);
DISPLAY 1.021277 (-1450 4725);
PAINT ORANGE (-1450 4725);
DISPLAY INVISIBLE (-1450 4725);
FORCEPROP 2 LAST CDS_SEC 1
J 0
(-1450 4675);
PAINT ORANGE (-1450 4675);
DISPLAY INVISIBLE (-1450 4675);
FORCEPROP 2 LAST CDS_LIB dev_discrete
J 0
(-1500 4525);
PAINT ORANGE (-1500 4525);
DISPLAY INVISIBLE (-1500 4525);
FORCEPROP 2 LAST BOM_COST MIO_BIOS_MEM
J 0
(-1450 4725);
DISPLAY 1.021277 (-1450 4725);
PAINT ORANGE (-1450 4725);
DISPLAY INVISIBLE (-1450 4725);
FORCEPROP 2 LAST CDS_LOCATION C2T1
J 0
(-1450 4625);
DISPLAY 0.617021 (-1450 4625);
PAINT AQUA (-1450 4625);
DISPLAY INVISIBLE (-1450 4625);
FORCEPROP 2 LAST ROOM SB_BMC_SPI_MUX
J 0
(-1450 4675);
DISPLAY 1.021277 (-1450 4675);
PAINT ORANGE (-1450 4675);
DISPLAY INVISIBLE (-1450 4675);
FORCEPROP 1 LAST PATH I94
J 0
(-1450 4675);
DISPLAY 0.978723 (-1450 4675);
PAINT WHITE (-1450 4675);
DISPLAY INVISIBLE (-1450 4675);
FORCEADD GND..1
(-1500 4275);
FORCEPROP 3 LASTPIN (-1500 4325) SIG_NAME GND\g
J 0
(-1490 4335);
DISPLAY 0.659574 (-1490 4335);
PAINT MONO (-1490 4335);
DISPLAY INVISIBLE (-1490 4335);
FORCEPROP 1 LAST HDL_POWER GND
J 0
(-1500 4425);
DISPLAY 0.872340 (-1500 4425);
PAINT GREEN (-1500 4425);
DISPLAY INVISIBLE (-1500 4425);
FORCEPROP 1 LAST PATH I95
J 0
(-1425 4275);
DISPLAY 0.872340 (-1425 4275);
PAINT AQUA (-1425 4275);
DISPLAY INVISIBLE (-1425 4275);
FORCEPROP 1 LAST BODY_TYPE PLUMBING
J 0
(-1545 4232);
DISPLAY 0.340426 (-1545 4232);
PAINT GREEN (-1545 4232);
DISPLAY INVISIBLE (-1545 4232);
FORCEPROP 1 LAST SIZE 1B
J 0
(-1425 4225);
DISPLAY 0.872340 (-1425 4225);
PAINT AQUA (-1425 4225);
DISPLAY INVISIBLE (-1425 4225);
FORCEPROP 2 LAST CDS_LIB mstr_symbols
J 0
(-1500 4275);
PAINT ORANGE (-1500 4275);
DISPLAY INVISIBLE (-1500 4275);
FORCEPROP 1 LAST VOLTAGE 0.0V
J 0
(-1545 4232);
DISPLAY 0.340426 (-1545 4232);
PAINT SKYBLUE (-1545 4232);
DISPLAY INVISIBLE (-1545 4232);
FORCEADD P3V3_STBY..1
(-1675 4775);
FORCEPROP 3 LASTPIN (-1675 4725) SIG_NAME P3V3_STBY\g
J 0
(-1665 4735);
DISPLAY 0.659574 (-1665 4735);
PAINT MONO (-1665 4735);
DISPLAY INVISIBLE (-1665 4735);
FORCEPROP 1 LAST HDL_POWER P3V3_STBY
J 0
(-1975 4650);
DISPLAY 0.872340 (-1975 4650);
PAINT ORANGE (-1975 4650);
DISPLAY INVISIBLE (-1975 4650);
FORCEPROP 1 LAST PATH I96
J 0
(-1630 4777);
DISPLAY 0.340426 (-1630 4777);
PAINT GREEN (-1630 4777);
DISPLAY INVISIBLE (-1630 4777);
FORCEPROP 1 LAST BODY_TYPE PLUMBING
J 0
(-1720 4732);
DISPLAY 0.340426 (-1720 4732);
PAINT GREEN (-1720 4732);
DISPLAY INVISIBLE (-1720 4732);
FORCEPROP 1 LAST SIZE 1B
J 0
(-1630 4797);
DISPLAY 0.340426 (-1630 4797);
PAINT GREEN (-1630 4797);
DISPLAY INVISIBLE (-1630 4797);
FORCEPROP 2 LAST CDS_LIB mstr_symbols
J 0
(-1675 4775);
PAINT ORANGE (-1675 4775);
DISPLAY INVISIBLE (-1675 4775);
FORCEPROP 1 LAST VOLTAGE 3.3V
J 0
(-1720 4732);
DISPLAY 0.340426 (-1720 4732);
PAINT SKYBLUE (-1720 4732);
DISPLAY INVISIBLE (-1720 4732);
FORCEADD GND..1
(-2275 3500);
FORCEPROP 3 LASTPIN (-2275 3550) SIG_NAME GND\g
J 0
(-2265 3560);
DISPLAY 0.659574 (-2265 3560);
PAINT MONO (-2265 3560);
DISPLAY INVISIBLE (-2265 3560);
FORCEPROP 1 LAST HDL_POWER GND
J 0
(-2275 3650);
DISPLAY 0.872340 (-2275 3650);
PAINT GREEN (-2275 3650);
DISPLAY INVISIBLE (-2275 3650);
FORCEPROP 1 LAST PATH I97
J 0
(-2200 3500);
DISPLAY 0.872340 (-2200 3500);
PAINT AQUA (-2200 3500);
DISPLAY INVISIBLE (-2200 3500);
FORCEPROP 1 LAST BODY_TYPE PLUMBING
J 0
(-2320 3457);
DISPLAY 0.340426 (-2320 3457);
PAINT GREEN (-2320 3457);
DISPLAY INVISIBLE (-2320 3457);
FORCEPROP 1 LAST SIZE 1B
J 0
(-2200 3450);
DISPLAY 0.872340 (-2200 3450);
PAINT AQUA (-2200 3450);
DISPLAY INVISIBLE (-2200 3450);
FORCEPROP 2 LAST CDS_LIB mstr_symbols
J 0
(-2275 3500);
PAINT ORANGE (-2275 3500);
DISPLAY INVISIBLE (-2275 3500);
FORCEPROP 1 LAST VOLTAGE 0.0V
J 0
(-2320 3457);
DISPLAY 0.340426 (-2320 3457);
PAINT SKYBLUE (-2320 3457);
DISPLAY INVISIBLE (-2320 3457);
FORCEADD GND..1
(-1725 3500);
FORCEPROP 3 LASTPIN (-1725 3550) SIG_NAME GND\g
J 0
(-1715 3560);
DISPLAY 0.659574 (-1715 3560);
PAINT MONO (-1715 3560);
DISPLAY INVISIBLE (-1715 3560);
FORCEPROP 1 LAST HDL_POWER GND
J 0
(-1725 3650);
DISPLAY 0.872340 (-1725 3650);
PAINT GREEN (-1725 3650);
DISPLAY INVISIBLE (-1725 3650);
FORCEPROP 1 LAST PATH I98
J 0
(-1650 3500);
DISPLAY 0.872340 (-1650 3500);
PAINT AQUA (-1650 3500);
DISPLAY INVISIBLE (-1650 3500);
FORCEPROP 1 LAST BODY_TYPE PLUMBING
J 0
(-1770 3457);
DISPLAY 0.340426 (-1770 3457);
PAINT GREEN (-1770 3457);
DISPLAY INVISIBLE (-1770 3457);
FORCEPROP 1 LAST SIZE 1B
J 0
(-1650 3450);
DISPLAY 0.872340 (-1650 3450);
PAINT AQUA (-1650 3450);
DISPLAY INVISIBLE (-1650 3450);
FORCEPROP 2 LAST CDS_LIB mstr_symbols
J 0
(-1725 3500);
PAINT ORANGE (-1725 3500);
DISPLAY INVISIBLE (-1725 3500);
FORCEPROP 1 LAST VOLTAGE 0.0V
J 0
(-1770 3457);
DISPLAY 0.340426 (-1770 3457);
PAINT SKYBLUE (-1770 3457);
DISPLAY INVISIBLE (-1770 3457);
FORCEADD TTL1G32_A..1
(-2275 1875);
FORCEPROP 2 LASTPIN (-2425 1925) $PN 1
J 2
(-2435 1935);
DISPLAY 0.617021 (-2435 1935);
PAINT ORANGE (-2435 1935);
FORCEPROP 2 LASTPIN (-2425 1825) $PN 2
J 2
(-2435 1835);
DISPLAY 0.617021 (-2435 1835);
PAINT ORANGE (-2435 1835);
FORCEPROP 2 LASTPIN (-2125 1875) $PN 4
J 0
(-2115 1885);
DISPLAY 0.617021 (-2115 1885);
PAINT ORANGE (-2115 1885);
FORCEPROP 1 LAST MATERIAL IC
J 0
(-2375 2050);
DISPLAY 0.617021 (-2375 2050);
PAINT SKYBLUE (-2375 2050);
FORCEPROP 1 LAST VALUE 74LVC1G32
J 0
(-2375 2000);
DISPLAY 0.617021 (-2375 2000);
PAINT SKYBLUE (-2375 2000);
FORCEPROP 1 LAST PART_NUMBER E60229-001
J 0
(-2375 1725);
DISPLAY 0.617021 (-2375 1725);
PAINT BLUE (-2375 1725);
FORCEPROP 1 LAST LOCATION U2T3
J 0
(-2375 2100);
DISPLAY 0.617021 (-2375 2100);
PAINT AQUA (-2375 2100);
FORCEPROP 1 LAST POWER_GROUP VCC=P3V3_STBY;GND=GND
J 0
(-2375 1675);
DISPLAY 0.617021 (-2375 1675);
PAINT ORANGE (-2375 1675);
FORCEPROP 2 LAST ROOM SB_BMC_SPI_MUX
J 0
(-2375 2150);
DISPLAY 1.021277 (-2375 2150);
PAINT ORANGE (-2375 2150);
DISPLAY INVISIBLE (-2375 2150);
FORCEPROP 1 LAST PATH I99
J 0
(-1925 2050);
DISPLAY 0.978723 (-1925 2050);
PAINT ORANGE (-1925 2050);
DISPLAY INVISIBLE (-1925 2050);
FORCEPROP 2 LAST CDS_LOCATION U2T3
J 0
(-2375 2100);
DISPLAY 0.617021 (-2375 2100);
PAINT AQUA (-2375 2100);
DISPLAY INVISIBLE (-2375 2100);
FORCEPROP 2 LAST SEC 1
J 0
(-2375 2150);
DISPLAY 0.680851 (-2375 2150);
PAINT MONO (-2375 2150);
DISPLAY INVISIBLE (-2375 2150);
FORCEPROP 2 LAST CDS_LIB mstr_ttl
J 0
(-2275 1875);
PAINT ORANGE (-2275 1875);
DISPLAY INVISIBLE (-2275 1875);
FORCEPROP 2 LAST SEC_TYPE SOT
J 0
(-2375 2150);
DISPLAY 1.021277 (-2375 2150);
PAINT ORANGE (-2375 2150);
DISPLAY INVISIBLE (-2375 2150);
FORCEPROP 2 LAST BOM_COST MIO_BIOS_MEM
J 0
(-2375 2200);
DISPLAY 1.021277 (-2375 2200);
PAINT ORANGE (-2375 2200);
DISPLAY INVISIBLE (-2375 2200);
FORCEPROP 1 LAST PACK_TYPE SOT
J 0
(-2375 2150);
DISPLAY 0.978723 (-2375 2150);
PAINT SKYBLUE (-2375 2150);
DISPLAY INVISIBLE (-2375 2150);
FORCEADD DESIGN_NOTE..1
(-5475 2800);
FORCEPROP 0 LAST L4 TO CONNECT BMC TO SPI FLASH
J 0
(-5675 2450);
DISPLAY 0.808511 (-5675 2450);
PAINT ORANGE (-5675 2450);
FORCEPROP 0 LAST L3 BMC SKU, THE BMC CAN PULL THIS NET HIGH
J 0
(-5675 2525);
DISPLAY 0.808511 (-5675 2525);
PAINT ORANGE (-5675 2525);
FORCEPROP 0 LAST L2 SO THAT PCH IS DEFAULT BUS AND FOR
J 0
(-5675 2600);
DISPLAY 0.808511 (-5675 2600);
PAINT ORANGE (-5675 2600);
FORCEPROP 0 LAST L1 FM_BIOS_SPI_BMC_CTRL NET SHOULD BE PULLED DOWN
J 0
(-5675 2675);
DISPLAY 0.808511 (-5675 2675);
PAINT ORANGE (-5675 2675);
FORCEPROP 1 LAST COMMENT_BODY TRUE
J 0
(-5450 2900);
DISPLAY 0.978723 (-5450 2900);
PAINT ORANGE (-5450 2900);
DISPLAY INVISIBLE (-5450 2900);
FORCEPROP 2 LAST CDS_LIB mstr_symbols
J 0
(-5475 2800);
PAINT MONO (-5475 2800);
DISPLAY INVISIBLE (-5475 2800);
FORCEADD CAD_NOTE..1
(-850 1550);
FORCEPROP 0 LAST L2 ON 74LVC1G32
J 2
(-600 1350);
DISPLAY 1.021277 (-600 1350);
PAINT ORANGE (-600 1350);
FORCEPROP 0 LAST L1 PLACE 0.1UF CAP NEXT TO VCC PIN
J 2
(-600 1425);
DISPLAY 1.021277 (-600 1425);
PAINT ORANGE (-600 1425);
FORCEPROP 1 LAST COMMENT_BODY TRUE
J 0
(-825 1650);
DISPLAY 0.978723 (-825 1650);
PAINT ORANGE (-825 1650);
DISPLAY INVISIBLE (-825 1650);
FORCEPROP 2 LAST CDS_LIB mstr_symbols
J 0
(-850 1550);
PAINT ORANGE (-850 1550);
DISPLAY INVISIBLE (-850 1550);
FORCEADD INTEL_CORP_BPAGE..1
(0 0);
FORCEPROP 1 LAST CDS_CON_LAST_MODIFIED Tue Dec 01 11:52:08 2015
J 0
(-1425 325);
DISPLAY 1.361702 (-1425 325);
PAINT GREEN (-1425 325);
DISPLAY INVISIBLE (-1425 325);
FORCEPROP 1 LAST CUSTOM_TXT_CDS <CURRENT_DESIGN_SHEET> OF <TOTAL_DESIGN_SHEETS>
J 0
(-500 25);
PAINT GREEN (-500 25);
FORCEPROP 1 LAST CUSTOM_TXT_CDS <CON_LAST_MODIFIED>
J 0
(-1925 350);
PAINT GREEN (-1925 350);
FORCEPROP 2 LAST CUSTOM_TXT_CDS <XR_PAGE_TITLE>
J 0
(-7890 5250);
DISPLAY 0.638298 (-7890 5250);
PAINT PINK (-7890 5250);
DISPLAY INVISIBLE (-7890 5250);
FORCEPROP 1 LAST SCH_TITLE PCH AND BMC SHARED SPI FLASH MUX
J 0
(-7950 50);
DISPLAY 1.212766 (-7950 50);
PAINT ORANGE (-7950 50);
FORCEPROP 1 LAST SCH_ADDRESS3 Santa Clara, CA 95052-8119
J 0
(-3975 25);
DISPLAY 0.617021 (-3975 25);
PAINT GREEN (-3975 25);
FORCEPROP 1 LAST SCH_ADDRESS2 P.O. BOX 58119
J 0
(-3975 75);
DISPLAY 0.617021 (-3975 75);
PAINT GREEN (-3975 75);
FORCEPROP 1 LAST SCH_ADDRESS1 2200 Mission College Blvd.
J 0
(-3975 125);
DISPLAY 0.617021 (-3975 125);
PAINT GREEN (-3975 125);
FORCEPROP 1 LAST SCH_NUMBER H4694802
J 0
(-1300 150);
DISPLAY 1.212766 (-1300 150);
PAINT YELLOW (-1300 150);
FORCEPROP 1 LAST SCH_DEPT BESD
J 1
(-4450 100);
DISPLAY 1.212766 (-4450 100);
PAINT YELLOW (-4450 100);
FORCEPROP 1 LAST SCH_REV 2.420
J 0
(-250 150);
DISPLAY 0.978723 (-250 150);
PAINT YELLOW (-250 150);
FORCEPROP 2 LAST PAGE_BORDER TRUE
J 0
(-7890 5250);
DISPLAY 0.851064 (-7890 5250);
PAINT PINK (-7890 5250);
DISPLAY INVISIBLE (-7890 5250);
FORCEPROP 2 LAST CDS_LIB mstr_symbols
J 0
(0 0);
DISPLAY 1.361702 (0 0);
PAINT ORANGE (0 0);
DISPLAY INVISIBLE (0 0);
FORCEPROP 1 LAST COMMENT_BODY TRUE
J 0
(12 12);
DISPLAY 0.617021 (12 12);
PAINT GREEN (12 12);
DISPLAY INVISIBLE (12 12);
FORCEPROP 2 LAST CDS_XR_PAGE_TITLE CR-154 : @BASEBOARD_FAB2_LIB.BASEBOARD_FAB2(SCH_1):PAGE154
J 0
(-7890 5250);
DISPLAY 0.638298 (-7890 5250);
PAINT PINK (-7890 5250);
DISPLAY INVISIBLE (-7890 5250);
FORCEADD CAD_NOTE..1
(-7525 3425);
FORCEPROP 0 LAST L1 PLACE R8F6 CLOSE TO U8F1
J 0
(-7675 3300);
DISPLAY 1.021277 (-7675 3300);
PAINT ORANGE (-7675 3300);
FORCEPROP 1 LAST COMMENT_BODY TRUE
J 0
(-7500 3525);
DISPLAY 0.978723 (-7500 3525);
PAINT ORANGE (-7500 3525);
DISPLAY INVISIBLE (-7500 3525);
FORCEPROP 2 LAST CDS_LIB mstr_symbols
J 0
(-7525 3425);
PAINT ORANGE (-7525 3425);
DISPLAY INVISIBLE (-7525 3425);
FORCEADD CAD_NOTE..1
(-875 2400);
FORCEPROP 0 LAST L2 ON 74LVC1G32
J 2
(-625 2200);
DISPLAY 1.021277 (-625 2200);
PAINT ORANGE (-625 2200);
FORCEPROP 0 LAST L1 PLACE 0.1UF CAP NEXT TO VCC PIN
J 2
(-625 2275);
DISPLAY 1.021277 (-625 2275);
PAINT ORANGE (-625 2275);
FORCEPROP 1 LAST COMMENT_BODY TRUE
J 0
(-850 2500);
DISPLAY 0.978723 (-850 2500);
PAINT ORANGE (-850 2500);
DISPLAY INVISIBLE (-850 2500);
FORCEPROP 2 LAST CDS_LIB mstr_symbols
J 0
(-875 2400);
PAINT ORANGE (-875 2400);
DISPLAY INVISIBLE (-875 2400);
WIRE 16 -1 (-3100 1325)(-3100 1375);
WIRE 16 -1 (-3100 2400)(-3100 2300);
WIRE 16 -1 (-3775 1850)(-3775 1975);
WIRE 16 -1 (-5400 4450)(-5400 4500);
WIRE 16 -1 (-5575 4500)(-5400 4500);
WIRE 16 -1 (-5575 4500)(-5575 4000);
WIRE 16 -1 (-5575 4550)(-5575 4500);
WIRE 16 -1 (-5575 4000)(-5700 4000);
WIRE 16 -1 (-6250 2500)(-6250 2650);
WIRE 16 -1 (-5400 4150)(-5400 4250);
WIRE 16 -1 (-375 2475)(-375 2325);
WIRE 16 -1 (-375 1975)(-375 2125);
WIRE 16 -1 (-375 1650)(-375 1500);
WIRE 16 -1 (-375 1150)(-375 1300);
WIRE 16 -1 (-3400 1975)(-3400 1850);
WIRE 16 -1 (-5625 3375)(-5625 3500);
WIRE 16 -1 (-5625 3500)(-5700 3500);
WIRE 16 -1 (-6175 4000)(-6100 4000);
WIRE 16 -1 (-6175 3375)(-6175 4000);
WIRE 16 -1 (-1500 4325)(-1500 4425);
WIRE 16 -1 (-1500 4625)(-1500 4675);
WIRE 16 -1 (-1675 4675)(-1500 4675);
WIRE 16 -1 (-1675 4675)(-1675 4175);
WIRE 16 -1 (-1675 4725)(-1675 4675);
WIRE 16 -1 (-1675 4175)(-1800 4175);
WIRE 16 -1 (-2275 4175)(-2200 4175);
WIRE 16 -1 (-2275 3550)(-2275 4175);
WIRE 16 -1 (-1725 3675)(-1800 3675);
WIRE 16 -1 (-1725 3550)(-1725 3675);
WIRE 16 -1 (-7275 3750)(-6100 3750);
FORCEPROP 2 LAST SIG_NAME SPI_BMC_DO
J 0
(-7250 3760);
DISPLAY 0.617021 (-7250 3760);
PAINT ORANGE (-7250 3760);
WIRE 16 -1 (-7275 3700)(-6100 3700);
FORCEPROP 2 LAST SIG_NAME SPI_PCH_CS0_N
J 0
(-7250 3710);
DISPLAY 0.617021 (-7250 3710);
PAINT ORANGE (-7250 3710);
WIRE 16 -1 (-7275 3800)(-6100 3800);
FORCEPROP 2 LAST SIG_NAME SPI_PCH_MOSI
J 0
(-7250 3810);
DISPLAY 0.617021 (-7250 3810);
PAINT ORANGE (-7250 3810);
WIRE 16 -1 (-7275 3650)(-6100 3650);
FORCEPROP 2 LAST SIG_NAME SPI_BMC_BT_CS1_N
J 0
(-7260 3660);
DISPLAY 0.680851 (-7260 3660);
PAINT ORANGE (-7260 3660);
WIRE 16 -1 (-7275 3550)(-6100 3550);
FORCEPROP 2 LAST SIG_NAME SPI_BMC_DI
J 0
(-7250 3560);
DISPLAY 0.617021 (-7250 3560);
PAINT ORANGE (-7250 3560);
WIRE 16 -1 (-6825 3600)(-7275 3600);
FORCEPROP 2 LAST SIG_NAME SPI_PCH_MISO
J 0
(-7275 3610);
DISPLAY 0.617021 (-7275 3610);
PAINT ORANGE (-7275 3610);
WIRE 16 -1 (-7600 4450)(-6300 4450);
WIRE 16 -1 (-7600 4450)(-7600 4550);
WIRE 16 -1 (-7600 4450)(-7600 4350);
WIRE 16 -1 (-6300 4450)(-6300 4550);
WIRE 16 -1 (-6300 4350)(-6300 4450);
WIRE 16 -1 (-7600 4350)(-6300 4350);
WIRE 16 -1 (-6300 4350)(-6300 4225);
WIRE 16 -1 (-7600 4550)(-6300 4550);
WIRE 16 -1 (-6300 4550)(-6300 4650);
WIRE 16 -1 (-7600 4225)(-7600 4350);
WIRE 16 -1 (-7600 4650)(-7600 4550);
WIRE 16 -1 (-7350 4650)(-7600 4650);
WIRE 16 -1 (-7600 4225)(-7350 4225);
WIRE 16 -1 (-6300 4650)(-6700 4650);
WIRE 16 -1 (-6700 4225)(-6300 4225);
WIRE 16 -1 (-6700 4650)(-6700 4225);
WIRE 16 -1 (-7050 4225)(-6700 4225);
WIRE 16 -1 (-6700 4650)(-7050 4650);
WIRE 16 -1 (-7350 4650)(-7350 4225);
WIRE 16 -1 (-7350 4225)(-7050 4225);
WIRE 16 -1 (-7050 4650)(-7350 4650);
WIRE 16 -1 (-7050 4650)(-7050 4225);
WIRE 16 -1 (-7275 3950)(-6100 3950);
FORCEPROP 2 LAST SIG_NAME FM_BIOS_SPI_BMC_CTRL
J 0
(-7250 3960);
DISPLAY 0.617021 (-7250 3960);
PAINT ORANGE (-7250 3960);
WIRE 16 -1 (-7275 3900)(-6100 3900);
FORCEPROP 2 LAST SIG_NAME SPI_PCH_CLK
J 0
(-7250 3910);
DISPLAY 0.617021 (-7250 3910);
PAINT ORANGE (-7250 3910);
WIRE 16 -1 (-7275 3850)(-6100 3850);
FORCEPROP 2 LAST SIG_NAME SPI_BMC_CLK
J 0
(-7250 3860);
DISPLAY 0.617021 (-7250 3860);
PAINT ORANGE (-7250 3860);
WIRE 16 -1 (-3475 2600)(-2825 2600);
WIRE 16 -1 (-3475 2600)(-3475 2750);
WIRE 16 -1 (-2825 3300)(-2825 2600);
WIRE 16 -1 (-2825 2600)(-2200 2600);
WIRE 16 -1 (-2200 2600)(-1450 2600);
WIRE 16 -1 (-2200 3300)(-2200 2600);
WIRE 16 -1 (-2200 3300)(-2825 3300);
WIRE 16 -1 (-2825 3300)(-3475 3300);
WIRE 16 -1 (-3475 2750)(-1450 2750);
WIRE 16 -1 (-3475 2750)(-3475 2925);
WIRE 16 -1 (-3475 2925)(-1450 2925);
WIRE 16 -1 (-3475 2925)(-3475 3175);
WIRE 16 -1 (-1450 2600)(-1450 2750);
WIRE 16 -1 (-1450 2750)(-1450 2925);
WIRE 16 -1 (-3475 3300)(-3475 3175);
WIRE 16 -1 (-1450 3300)(-2200 3300);
WIRE 16 -1 (-1450 3175)(-1450 3300);
WIRE 16 -1 (-3475 3175)(-1450 3175);
WIRE 16 -1 (-1450 2925)(-1450 3175);
WIRE 16 -1 (-3450 4125)(-2200 4125);
FORCEPROP 2 LAST SIG_NAME FM_BIOS_SPI_BMC_CTRL
J 2
(-3025 4135);
DISPLAY 0.617021 (-3025 4135);
PAINT ORANGE (-3025 4135);
WIRE 16 -1 (-1800 4075)(-1000 4075);
FORCEPROP 2 LAST SIG_NAME SPI_BIOS_SOCKET_IO2
J 2
(-1000 4085);
DISPLAY 0.617021 (-1000 4085);
PAINT ORANGE (-1000 4085);
WIRE 16 -1 (-1800 3975)(-1000 3975);
FORCEPROP 2 LAST SIG_NAME SPI_BIOS_SOCKET_IO3
J 2
(-1000 3985);
DISPLAY 0.617021 (-1000 3985);
PAINT ORANGE (-1000 3985);
WIRE 16 -1 (-1800 3875)(-1000 3875);
FORCEPROP 2 LAST SIG_NAME TP_SPI_SWITCH1_9
J 2
(-1000 3885);
DISPLAY 0.617021 (-1000 3885);
PAINT ORANGE (-1000 3885);
FORCEPROP 2 LASTPROP $XRERR UNIQUE?
J 0
(-970 3875);
DISPLAY 0.638298 (-970 3875);
PAINT MONO (-970 3875);
DISPLAY INVISIBLE (-970 3875);
WIRE 16 -1 (-4225 1100)(-3775 1100);
FORCEPROP 2 LAST SIG_NAME SPI_SWITCH_CS0_N
J 0
(-4185 1110);
DISPLAY 0.617021 (-4185 1110);
PAINT ORANGE (-4185 1110);
WIRE 16 -1 (-3775 1100)(-2675 1100);
WIRE 16 -1 (-3775 1650)(-3775 1100);
WIRE 16 -1 (-2425 1100)(-2675 1100);
WIRE 16 -1 (-2675 1825)(-2675 1100);
WIRE 16 -1 (-2675 1825)(-2425 1825);
WIRE 16 -1 (-3500 1200)(-2425 1200);
WIRE 16 -1 (-3500 1200)(-3500 1475);
FORCEPROP 2 LAST SIG_NAME FM_BACKUP_BIOS_SEL_N
J 0
(-4235 1485);
DISPLAY 0.617021 (-4235 1485);
PAINT ORANGE (-4235 1485);
WIRE 16 -1 (-3500 1475)(-3400 1475);
WIRE 16 -1 (-3500 1475)(-4225 1475);
WIRE 16 -1 (-3400 1650)(-3400 1475);
WIRE 16 -1 (-3400 1475)(-3300 1475);
WIRE 16 -1 (-6100 3600)(-6625 3600);
FORCEPROP 2 LAST SIG_NAME SPI_PCH_MISO_R
J 2
(-6200 3610);
DISPLAY 0.617021 (-6200 3610);
PAINT ORANGE (-6200 3610);
FORCEPROP 2 LASTPROP $XRERR UNIQUE?
J 0
(-6440 3610);
DISPLAY 0.638298 (-6440 3610);
PAINT MONO (-6440 3610);
DISPLAY INVISIBLE (-6440 3610);
WIRE 16 -1 (-2825 3975)(-2200 3975);
FORCEPROP 2 LAST SIG_NAME SPI_PCH_IO3_R1
J 2
(-2275 3985);
DISPLAY 0.617021 (-2275 3985);
PAINT ORANGE (-2275 3985);
FORCEPROP 2 LASTPROP $XRERR UNIQUE?
J 0
(-2515 3985);
DISPLAY 0.638298 (-2515 3985);
PAINT MONO (-2515 3985);
DISPLAY INVISIBLE (-2515 3985);
WIRE 16 -1 (-2675 3875)(-2200 3875);
FORCEPROP 2 LAST SIG_NAME TP_SPI_SWITCH1_11
J 0
(-2650 3885);
DISPLAY 0.617021 (-2650 3885);
PAINT ORANGE (-2650 3885);
FORCEPROP 2 LASTPROP $XRERR UNIQUE?
J 0
(-2915 3875);
DISPLAY 0.638298 (-2915 3875);
PAINT MONO (-2915 3875);
DISPLAY INVISIBLE (-2915 3875);
WIRE 16 -1 (-2675 3825)(-2200 3825);
FORCEPROP 2 LAST SIG_NAME TP_SPI_SWITCH1_10
J 0
(-2650 3835);
DISPLAY 0.617021 (-2650 3835);
PAINT ORANGE (-2650 3835);
FORCEPROP 2 LASTPROP $XRERR UNIQUE?
J 0
(-2915 3825);
DISPLAY 0.638298 (-2915 3825);
PAINT MONO (-2915 3825);
DISPLAY INVISIBLE (-2915 3825);
WIRE 16 -1 (-2675 3775)(-2200 3775);
FORCEPROP 2 LAST SIG_NAME TP_SPI_SWITCH1_14
J 0
(-2650 3785);
DISPLAY 0.617021 (-2650 3785);
PAINT ORANGE (-2650 3785);
FORCEPROP 2 LASTPROP $XRERR UNIQUE?
J 0
(-2915 3775);
DISPLAY 0.638298 (-2915 3775);
PAINT MONO (-2915 3775);
DISPLAY INVISIBLE (-2915 3775);
WIRE 16 -1 (-2675 3725)(-2200 3725);
FORCEPROP 2 LAST SIG_NAME TP_SPI_SWITCH1_13
J 0
(-2650 3735);
DISPLAY 0.617021 (-2650 3735);
PAINT ORANGE (-2650 3735);
FORCEPROP 2 LASTPROP $XRERR UNIQUE?
J 0
(-2915 3725);
DISPLAY 0.638298 (-2915 3725);
PAINT MONO (-2915 3725);
DISPLAY INVISIBLE (-2915 3725);
WIRE 16 -1 (-3025 3975)(-3450 3975);
FORCEPROP 2 LAST SIG_NAME SPI_PCH_IO3
J 0
(-3435 3985);
DISPLAY 0.617021 (-3435 3985);
PAINT ORANGE (-3435 3985);
WIRE 16 -1 (-3025 4075)(-3450 4075);
FORCEPROP 2 LAST SIG_NAME SPI_PCH_IO2
J 0
(-3435 4085);
DISPLAY 0.617021 (-3435 4085);
PAINT ORANGE (-3435 4085);
WIRE 16 -1 (-6250 3000)(-5425 3000);
FORCEPROP 2 LAST SIG_NAME FM_BIOS_SPI_BMC_CTRL
J 0
(-6160 3010);
DISPLAY 0.617021 (-6160 3010);
PAINT ORANGE (-6160 3010);
WIRE 16 -1 (-6250 2850)(-6250 3000);
WIRE 16 -1 (-5700 3900)(-4900 3900);
FORCEPROP 2 LAST SIG_NAME SPI_SWITCH_CLK
J 2
(-4900 3910);
DISPLAY 0.617021 (-4900 3910);
PAINT ORANGE (-4900 3910);
WIRE 16 -1 (-5700 3800)(-4900 3800);
FORCEPROP 2 LAST SIG_NAME SPI_SWITCH_MOSI
J 2
(-4900 3810);
DISPLAY 0.617021 (-4900 3810);
PAINT ORANGE (-4900 3810);
WIRE 16 -1 (-5700 3700)(-4900 3700);
FORCEPROP 2 LAST SIG_NAME SPI_SWITCH_CS0_N
J 2
(-4900 3710);
DISPLAY 0.617021 (-4900 3710);
PAINT ORANGE (-4900 3710);
WIRE 16 -1 (-5700 3600)(-4900 3600);
FORCEPROP 2 LAST SIG_NAME SPI_SWITCH_MISO
J 2
(-4900 3610);
DISPLAY 0.617021 (-4900 3610);
PAINT ORANGE (-4900 3610);
WIRE 16 -1 (-3100 1775)(-3100 1925);
FORCEPROP 2 LAST SIG_NAME FM_DUAL_BIOS_SEL_N
J 0
(-3085 1950);
DISPLAY 0.617021 (-3085 1950);
PAINT ORANGE (-3085 1950);
FORCEPROP 2 LASTPROP $XRERR UNIQUE?
J 0
(-3325 1950);
DISPLAY 0.638298 (-3325 1950);
PAINT MONO (-3325 1950);
DISPLAY INVISIBLE (-3325 1950);
WIRE 16 -1 (-3100 1925)(-3100 2100);
WIRE 16 -1 (-3100 1925)(-2425 1925);
WIRE 16 -1 (-2675 4025)(-2200 4025);
FORCEPROP 2 LAST SIG_NAME TP_SPI_SWITCH1_3
J 0
(-2650 4035);
DISPLAY 0.617021 (-2650 4035);
PAINT ORANGE (-2650 4035);
FORCEPROP 2 LASTPROP $XRERR UNIQUE?
J 0
(-2915 4025);
DISPLAY 0.638298 (-2915 4025);
PAINT MONO (-2915 4025);
DISPLAY INVISIBLE (-2915 4025);
WIRE 16 -1 (-2825 4075)(-2200 4075);
FORCEPROP 2 LAST SIG_NAME SPI_PCH_IO2_R1
J 2
(-2275 4085);
DISPLAY 0.617021 (-2275 4085);
PAINT ORANGE (-2275 4085);
FORCEPROP 2 LASTPROP $XRERR UNIQUE?
J 0
(-2515 4085);
DISPLAY 0.638298 (-2515 4085);
PAINT MONO (-2515 4085);
DISPLAY INVISIBLE (-2515 4085);
WIRE 16 -1 (-2675 3925)(-2200 3925);
FORCEPROP 2 LAST SIG_NAME TP_SPI_SWITCH1_6
J 0
(-2650 3935);
DISPLAY 0.617021 (-2650 3935);
PAINT ORANGE (-2650 3935);
FORCEPROP 2 LASTPROP $XRERR UNIQUE?
J 0
(-2915 3925);
DISPLAY 0.638298 (-2915 3925);
PAINT MONO (-2915 3925);
DISPLAY INVISIBLE (-2915 3925);
WIRE 16 -1 (-2125 1150)(-1550 1150);
FORCEPROP 2 LAST SIG_NAME SPI_CS0_SECONDARY_N
J 0
(-2075 1160);
DISPLAY 0.617021 (-2075 1160);
PAINT ORANGE (-2075 1160);
FORCEPROP 2 LASTPROP $XRERR UNIQUE?
J 0
(-2315 1160);
DISPLAY 0.638298 (-2315 1160);
PAINT MONO (-2315 1160);
DISPLAY INVISIBLE (-2315 1160);
WIRE 16 -1 (-1550 1875)(-2125 1875);
FORCEPROP 2 LAST SIG_NAME SPI_CS0_PRIMARY_N
J 0
(-2050 1885);
DISPLAY 0.617021 (-2050 1885);
PAINT ORANGE (-2050 1885);
FORCEPROP 2 LASTPROP $XRERR UNIQUE?
J 0
(-2290 1885);
DISPLAY 0.638298 (-2290 1885);
PAINT MONO (-2290 1885);
DISPLAY INVISIBLE (-2290 1885);
WIRE 16 -1 (-1350 1875)(-875 1875);
FORCEPROP 2 LAST SIG_NAME SPI_CS0_PRIMARY_R_N
J 2
(-875 1885);
DISPLAY 0.617021 (-875 1885);
PAINT ORANGE (-875 1885);
WIRE 16 -1 (-1350 1150)(-875 1150);
FORCEPROP 2 LAST SIG_NAME SPI_CS0_SECONDARY_R_N
J 2
(-900 1160);
DISPLAY 0.617021 (-900 1160);
PAINT ORANGE (-900 1160);
WIRE 16 -1 (-1800 3775)(-1000 3775);
FORCEPROP 2 LAST SIG_NAME TP_SPI_SWITCH1_12
J 2
(-1000 3785);
DISPLAY 0.617021 (-1000 3785);
PAINT ORANGE (-1000 3785);
FORCEPROP 2 LASTPROP $XRERR UNIQUE?
J 0
(-970 3775);
DISPLAY 0.638298 (-970 3775);
PAINT MONO (-970 3775);
DISPLAY INVISIBLE (-970 3775);
DOT 1 (-1450 2925);
DOT 1 (-1450 2750);
DOT 1 (-3400 1475);
DOT 1 (-3775 1100);
DOT 1 (-2675 1100);
DOT 1 (-3500 1475);
DOT 1 (-2825 2600);
DOT 1 (-3475 2925);
DOT 1 (-5575 4500);
DOT 1 (-1675 4675);
DOT 1 (-7600 4350);
DOT 1 (-7600 4450);
DOT 1 (-7350 4225);
DOT 1 (-6300 4350);
DOT 1 (-7050 4225);
DOT 1 (-7350 4650);
DOT 1 (-6300 4450);
DOT 1 (-7600 4550);
DOT 1 (-6300 4550);
DOT 1 (-7050 4650);
DOT 1 (-6700 4225);
DOT 1 (-6700 4650);
DOT 1 (-2825 3300);
DOT 1 (-2200 3300);
DOT 1 (-2200 2600);
DOT 1 (-1450 3175);
DOT 1 (-3475 3175);
DOT 1 (-3100 1925);
DOT 1 (-3475 2750);
FORCENOTE
$CDS_IMAGE|SPI.jpg|2222|2388
(-6775 1425) 0;
DISPLAY CENTER (-6775 1425);
PAINT MONO (-6775 1425);
FORCENOTE
BIOS
(-2025 3200) 0;
DISPLAY LEFT (-2025 3200);
DISPLAY 0.808511 (-2025 3200);
PAINT PURPLE (-2025 3200);
FORCENOTE
X
(-1975 2650) 0;
DISPLAY LEFT (-1975 2650);
DISPLAY 1.021277 (-1975 2650);
PAINT PURPLE (-1975 2650);
FORCENOTE
SECONDARY
(-2075 2825) 0;
DISPLAY LEFT (-2075 2825);
DISPLAY 1.021277 (-2075 2825);
PAINT PURPLE (-2075 2825);
FORCENOTE
PRIMARY
(-2075 3050) 0;
DISPLAY LEFT (-2075 3050);
DISPLAY 1.021277 (-2075 3050);
PAINT PURPLE (-2075 3050);
FORCENOTE
(DEFAULT)
(-2075 2975) 0;
DISPLAY LEFT (-2075 2975);
DISPLAY 1.021277 (-2075 2975);
PAINT PURPLE (-2075 2975);
FORCENOTE
H
(-2575 2650) 0;
DISPLAY LEFT (-2575 2650);
DISPLAY 1.021277 (-2575 2650);
PAINT PURPLE (-2575 2650);
FORCENOTE
L
(-2575 3000) 0;
DISPLAY LEFT (-2575 3000);
DISPLAY 1.021277 (-2575 3000);
PAINT PURPLE (-2575 3000);
FORCENOTE
L
(-2575 2825) 0;
DISPLAY LEFT (-2575 2825);
DISPLAY 1.021277 (-2575 2825);
PAINT PURPLE (-2575 2825);
FORCENOTE
(DEFAULT)
(-3325 2975) 0;
DISPLAY LEFT (-3325 2975);
DISPLAY 1.021277 (-3325 2975);
PAINT PURPLE (-3325 2975);
FORCENOTE
H
(-3200 3050) 0;
DISPLAY LEFT (-3200 3050);
DISPLAY 1.021277 (-3200 3050);
PAINT PURPLE (-3200 3050);
FORCENOTE
X
(-3200 2650) 0;
DISPLAY LEFT (-3200 2650);
DISPLAY 1.021277 (-3200 2650);
PAINT PURPLE (-3200 2650);
FORCENOTE
L
(-3200 2825) 0;
DISPLAY LEFT (-3200 2825);
DISPLAY 1.021277 (-3200 2825);
PAINT PURPLE (-3200 2825);
FORCENOTE
Y
(-6925 4575) 0;
DISPLAY LEFT (-6925 4575);
DISPLAY 1.021277 (-6925 4575);
PAINT PURPLE (-6925 4575);
FORCENOTE
1
(-6850 4250) 0;
DISPLAY LEFT (-6850 4250);
DISPLAY 0.808511 (-6850 4250);
PAINT PURPLE (-6850 4250);
FORCENOTE
O
(-6850 4350) 0;
DISPLAY LEFT (-6850 4350);
DISPLAY 0.808511 (-6850 4350);
PAINT PURPLE (-6850 4350);
FORCENOTE
N
(-6875 4550) 0;
DISPLAY LEFT (-6875 4550);
DISPLAY 0.808511 (-6875 4550);
PAINT PURPLE (-6875 4550);
FORCENOTE
N
(-6900 4375) 0;
DISPLAY LEFT (-6900 4375);
DISPLAY 1.021277 (-6900 4375);
PAINT PURPLE (-6900 4375);
FORCENOTE
N
(-6900 4275) 0;
DISPLAY LEFT (-6900 4275);
DISPLAY 1.021277 (-6900 4275);
PAINT PURPLE (-6900 4275);
FORCENOTE
HIZ
(-6925 4475) 0;
DISPLAY LEFT (-6925 4475);
DISPLAY 1.021277 (-6925 4475);
PAINT PURPLE (-6925 4475);
FORCENOTE
S
(-7250 4575) 0;
DISPLAY LEFT (-7250 4575);
DISPLAY 1.021277 (-7250 4575);
PAINT PURPLE (-7250 4575);
FORCENOTE
X
(-7250 4475) 0;
DISPLAY LEFT (-7250 4475);
DISPLAY 1.021277 (-7250 4475);
PAINT PURPLE (-7250 4475);
FORCENOTE
H
(-7250 4275) 0;
DISPLAY LEFT (-7250 4275);
DISPLAY 1.021277 (-7250 4275);
PAINT PURPLE (-7250 4275);
FORCENOTE
L
(-7250 4375) 0;
DISPLAY LEFT (-7250 4375);
DISPLAY 1.021277 (-7250 4375);
PAINT PURPLE (-7250 4375);
FORCENOTE
L
(-7525 4375) 0;
DISPLAY LEFT (-7525 4375);
DISPLAY 1.021277 (-7525 4375);
PAINT PURPLE (-7525 4375);
FORCENOTE
L
(-7525 4275) 0;
DISPLAY LEFT (-7525 4275);
DISPLAY 1.021277 (-7525 4275);
PAINT PURPLE (-7525 4275);
FORCENOTE
FM_BACKUP_BIOS_SEL_N
(-3450 3200) 0;
DISPLAY LEFT (-3450 3200);
DISPLAY 0.808511 (-3450 3200);
PAINT PURPLE (-3450 3200);
FORCENOTE
SPI_SWITCH_CS0_N
(-2700 3200) 0;
DISPLAY LEFT (-2700 3200);
DISPLAY 0.808511 (-2700 3200);
PAINT PURPLE (-2700 3200);
FORCENOTE
PI3B3257A TRUTH TABLE
(-7600 4725) 0;
DISPLAY LEFT (-7600 4725);
DISPLAY 1.021277 (-7600 4725);
PAINT PURPLE (-7600 4725);
FORCENOTE
H
(-7525 4475) 0;
DISPLAY LEFT (-7525 4475);
DISPLAY 1.021277 (-7525 4475);
PAINT PURPLE (-7525 4475);
FORCENOTE
S=1
(-6650 4275) 0;
DISPLAY LEFT (-6650 4275);
DISPLAY 1.021277 (-6650 4275);
PAINT PURPLE (-6650 4275);
FORCENOTE
S=0
(-6650 4375) 0;
DISPLAY LEFT (-6650 4375);
DISPLAY 1.021277 (-6650 4375);
PAINT PURPLE (-6650 4375);
FORCENOTE
DISABLE
(-6650 4475) 0;
DISPLAY LEFT (-6650 4475);
DISPLAY 1.021277 (-6650 4475);
PAINT PURPLE (-6650 4475);
FORCENOTE
FUNCTION
(-6650 4575) 0;
DISPLAY LEFT (-6650 4575);
DISPLAY 1.021277 (-6650 4575);
PAINT PURPLE (-6650 4575);
FORCENOTE
E#
(-7525 4575) 0;
DISPLAY LEFT (-7525 4575);
DISPLAY 1.021277 (-7525 4575);
PAINT PURPLE (-7525 4575);
QUIT
